FILE_TYPE = MACRO_DRAWING;
SET COLOR_WIRE YELLOW;
SET COLOR_PROP ORANGE;
SET COLOR_DOT WHITE;
SET COLOR_ARC YELLOW;
SET COLOR_BODY GREEN;
SET COLOR_NOTE PURPLE;
SET PROP_DISPLAY VALUE;
SET PAGE_NUMBER P272;
FORCEADD UNIVERSAL_GND..1
(-2775 -2275);
FORCEPROP 3 LASTPIN (-2775 -2225) SIG_NAME GND\g
J 0
(-2765 -2215);
DISPLAY 0.659574 (-2765 -2215);
PAINT MONO (-2765 -2215);
DISPLAY INVISIBLE (-2765 -2215);
FORCEPROP 1 LAST HDL_POWER GND
J 1
(-2750 -2350);
DISPLAY 0.872340 (-2750 -2350);
PAINT GREEN (-2750 -2350);
DISPLAY INVISIBLE (-2750 -2350);
FORCEPROP 2 LAST CDS_LIB logical_power
J 0
(-2775 -2275);
PAINT MONO (-2775 -2275);
DISPLAY INVISIBLE (-2775 -2275);
FORCEPROP 1 LAST PATH I1
J 0
(-2700 -2275);
DISPLAY 0.872340 (-2700 -2275);
PAINT AQUA (-2700 -2275);
DISPLAY INVISIBLE (-2700 -2275);
FORCEADD ISL99390FRZTR5935..1
(-850 -1550);
FORCEPROP 1 LAST PART_NUMBER AL099390004
J 0
(-1150 -750);
DISPLAY 0.617021 (-1150 -750);
PAINT BLUE (-1150 -750);
DISPLAY INVISIBLE (-1150 -750);
FORCEPROP 2 LAST VALUE ISL99390FRZ-TR5935
J 0
(-1150 -600);
DISPLAY 0.617021 (-1150 -600);
PAINT SKYBLUE (-1150 -600);
FORCEPROP 1 LAST MATERIAL IC
J 0
(-1150 -825);
DISPLAY 0.617021 (-1150 -825);
PAINT SKYBLUE (-1150 -825);
FORCEPROP 2 LAST PART_TYPE SMLF
J 0
(-1150 -550);
DISPLAY 0.638298 (-1150 -550);
FORCEPROP 1 LAST LOCATION PU27_P1_4
J 0
(-1150 -675);
DISPLAY 0.617021 (-1150 -675);
PAINT AQUA (-1150 -675);
FORCEPROP 2 LASTPIN (-450 -2000) $PN 2
J 0
(-440 -1990);
DISPLAY 0.617021 (-440 -1990);
PAINT MONO (-440 -1990);
FORCEPROP 2 LASTPIN (-450 -1200) $PN 33
J 0
(-440 -1190);
DISPLAY 0.617021 (-440 -1190);
PAINT MONO (-440 -1190);
FORCEPROP 2 LASTPIN (-1300 -1800) $PN 31
J 2
(-1310 -1790);
DISPLAY 0.617021 (-1310 -1790);
PAINT MONO (-1310 -1790);
FORCEPROP 2 LASTPIN (-1300 -1400) $PN 35
J 2
(-1310 -1390);
DISPLAY 0.617021 (-1310 -1390);
PAINT MONO (-1310 -1390);
FORCEPROP 2 LASTPIN (-450 -1850) $PN 6
J 0
(-440 -1840);
DISPLAY 0.617021 (-440 -1840);
PAINT MONO (-440 -1840);
FORCEPROP 2 LASTPIN (-450 -1900) $PN 41
J 0
(-440 -1890);
DISPLAY 0.617021 (-440 -1890);
PAINT MONO (-440 -1890);
FORCEPROP 2 LASTPIN (-1300 -1550) $PN 38
J 2
(-1310 -1540);
DISPLAY 0.617021 (-1310 -1540);
PAINT MONO (-1310 -1540);
FORCEPROP 2 LASTPIN (-1300 -1850) $PN 37
J 2
(-1310 -1840);
DISPLAY 0.617021 (-1310 -1840);
PAINT MONO (-1310 -1840);
FORCEPROP 2 LASTPIN (-450 -2050) $PN 5
J 0
(-440 -2040);
DISPLAY 0.617021 (-440 -2040);
PAINT MONO (-440 -2040);
FORCEPROP 2 LASTPIN (-450 -2100) $PN 7_9-20_24
J 0
(-440 -2090);
DISPLAY 0.617021 (-440 -2090);
PAINT MONO (-440 -2090);
FORCEPROP 2 LASTPIN (-450 -2150) $PN 40
J 0
(-440 -2140);
DISPLAY 0.617021 (-440 -2140);
PAINT MONO (-440 -2140);
FORCEPROP 2 LASTPIN (-450 -1450) $PN 32
J 0
(-440 -1440);
DISPLAY 0.617021 (-440 -1440);
PAINT MONO (-440 -1440);
FORCEPROP 2 LASTPIN (-1300 -900) $PN 4
J 2
(-1310 -890);
DISPLAY 0.617021 (-1310 -890);
PAINT MONO (-1310 -890);
FORCEPROP 2 LASTPIN (-1300 -2150) $PN 34
J 2
(-1310 -2140);
DISPLAY 0.617021 (-1310 -2140);
PAINT MONO (-1310 -2140);
FORCEPROP 2 LASTPIN (-1300 -1650) $PN 39
J 2
(-1310 -1640);
DISPLAY 0.617021 (-1310 -1640);
PAINT MONO (-1310 -1640);
FORCEPROP 2 LASTPIN (-450 -1550) $PN 10_19
J 0
(-440 -1540);
DISPLAY 0.617021 (-440 -1540);
PAINT MONO (-440 -1540);
FORCEPROP 2 LASTPIN (-1300 -2050) $PN 36
J 2
(-1310 -2040);
DISPLAY 0.617021 (-1310 -2040);
PAINT MONO (-1310 -2040);
FORCEPROP 2 LASTPIN (-1300 -1200) $PN 3
J 2
(-1310 -1190);
DISPLAY 0.617021 (-1310 -1190);
PAINT MONO (-1310 -1190);
FORCEPROP 2 LASTPIN (-450 -900) $PN 25_29
J 0
(-440 -890);
DISPLAY 0.617021 (-440 -890);
PAINT MONO (-440 -890);
FORCEPROP 2 LASTPIN (-450 -950) $PN 30
J 0
(-440 -940);
DISPLAY 0.617021 (-440 -940);
PAINT MONO (-440 -940);
FORCEPROP 2 LASTPIN (-450 -1800) $PN 1
J 0
(-440 -1790);
DISPLAY 0.617021 (-440 -1790);
PAINT MONO (-440 -1790);
FORCEPROP 1 LAST NEEDS_NO_SIZE TRUE
J 0
(-850 -1550);
DISPLAY 0.723404 (-850 -1550);
PAINT GREEN (-850 -1550);
DISPLAY INVISIBLE (-850 -1550);
FORCEPROP 1 LAST CDS_LMAN_SYM_OUTLINE -300,700,250,-650
J 0
(-850 -1550);
DISPLAY 0.468085 (-850 -1550);
PAINT GREEN (-850 -1550);
DISPLAY INVISIBLE (-850 -1550);
FORCEPROP 2 LAST CDS_LIB pure_quanta
J 0
(-850 -1550);
DISPLAY INVISIBLE (-850 -1550);
FORCEPROP 2 LAST SEC_TYPE 
J 0
(-1150 -625);
DISPLAY 1.021277 (-1150 -625);
DISPLAY INVISIBLE (-1150 -625);
FORCEPROP 1 LAST PATH I10
J 0
(-850 -1550);
DISPLAY 0.723404 (-850 -1550);
PAINT GREEN (-850 -1550);
DISPLAY INVISIBLE (-850 -1550);
FORCEPROP 2 LAST SEC 1
J 0
(-1150 -625);
DISPLAY 0.680851 (-1150 -625);
PAINT MONO (-1150 -625);
DISPLAY INVISIBLE (-1150 -625);
FORCEADD Q_CAP..1
(-2375 -1050);
FORCEPROP 1 LAST PART_NUMBER CH5222KEB01
J 0
(-2325 -1225);
DISPLAY 0.617021 (-2325 -1225);
PAINT BLUE (-2325 -1225);
DISPLAY INVISIBLE (-2325 -1225);
FORCEPROP 1 LAST PACK_TYPE C0402
J 0
(-2325 -1175);
DISPLAY 0.617021 (-2325 -1175);
PAINT SKYBLUE (-2325 -1175);
FORCEPROP 1 LAST VOLTAGE 10V
J 0
(-2325 -1025);
DISPLAY 0.617021 (-2325 -1025);
PAINT SKYBLUE (-2325 -1025);
FORCEPROP 1 LAST VALUE 2.2UF
J 0
(-2325 -975);
DISPLAY 0.617021 (-2325 -975);
PAINT SKYBLUE (-2325 -975);
FORCEPROP 1 LAST TOLERANCE 10%
J 0
(-2325 -1075);
DISPLAY 0.617021 (-2325 -1075);
PAINT SKYBLUE (-2325 -1075);
FORCEPROP 1 LAST MATERIAL X6S
J 0
(-2325 -1125);
DISPLAY 0.617021 (-2325 -1125);
PAINT SKYBLUE (-2325 -1125);
FORCEPROP 1 LAST LOCATION PC523
J 0
(-2325 -925);
DISPLAY 0.617021 (-2325 -925);
PAINT AQUA (-2325 -925);
FORCEPROP 1 LASTPIN (-2375 -950) $PN 1
J 0
(-2365 -970);
DISPLAY 0.617021 (-2365 -970);
PAINT MONO (-2365 -970);
FORCEPROP 1 LASTPIN (-2375 -1150) $PN 2
J 0
(-2365 -1170);
DISPLAY 0.617021 (-2365 -1170);
PAINT MONO (-2365 -1170);
FORCEPROP 2 LAST CDS_LIB pure_quanta
J 0
(-2375 -1050);
DISPLAY INVISIBLE (-2375 -1050);
FORCEPROP 1 LAST PATH I11
J 0
(-2325 -900);
DISPLAY 0.978723 (-2325 -900);
PAINT WHITE (-2325 -900);
DISPLAY INVISIBLE (-2325 -900);
FORCEPROP 1 LAST LOCATION PC523
J 0
(-2325 -875);
DISPLAY 1.021277 (-2325 -875);
PAINT AQUA (-2325 -875);
DISPLAY INVISIBLE (-2325 -875);
FORCEPROP 0 LAST $SEC 1
J 0
(-2325 -875);
DISPLAY 0.680851 (-2325 -875);
PAINT MONO (-2325 -875);
DISPLAY INVISIBLE (-2325 -875);
FORCEPROP 0 LAST CDS_SEC 1
J 0
(-2325 -875);
DISPLAY 1.021277 (-2325 -875);
DISPLAY INVISIBLE (-2325 -875);
FORCEADD Q_RES..2
(-2375 -550);
FORCEPROP 1 LAST PART_NUMBER CS-2202FB01
J 0
(-2335 -675);
DISPLAY 0.617021 (-2335 -675);
PAINT BLUE (-2335 -675);
DISPLAY INVISIBLE (-2335 -675);
FORCEPROP 1 LAST PACK_TYPE 0402LF
J 0
(-2335 -725);
DISPLAY 0.617021 (-2335 -725);
PAINT SKYBLUE (-2335 -725);
FORCEPROP 1 LAST VALUE 2.2
J 0
(-2330 -475);
DISPLAY 0.617021 (-2330 -475);
PAINT SKYBLUE (-2330 -475);
FORCEPROP 1 LAST TOLERANCE 1%
J 0
(-2330 -525);
DISPLAY 0.617021 (-2330 -525);
PAINT SKYBLUE (-2330 -525);
FORCEPROP 1 LAST MATERIAL CHIP
J 0
(-2335 -625);
DISPLAY 0.617021 (-2335 -625);
PAINT SKYBLUE (-2335 -625);
FORCEPROP 1 LAST WATTAGE 1/16W
J 0
(-2335 -575);
DISPLAY 0.617021 (-2335 -575);
PAINT SKYBLUE (-2335 -575);
FORCEPROP 1 LAST LOCATION PR299
J 0
(-2330 -425);
DISPLAY 0.617021 (-2330 -425);
PAINT AQUA (-2330 -425);
FORCEPROP 1 LASTPIN (-2375 -450) $PN 1
J 0
(-2370 -488);
DISPLAY 0.617021 (-2370 -488);
PAINT MONO (-2370 -488);
FORCEPROP 1 LASTPIN (-2375 -650) $PN 2
J 0
(-2370 -640);
DISPLAY 0.617021 (-2370 -640);
PAINT MONO (-2370 -640);
FORCEPROP 2 LAST CDS_LIB pure_quanta
J 0
(-2375 -550);
DISPLAY INVISIBLE (-2375 -550);
FORCEPROP 1 LAST PATH I12
J 0
(-2325 -375);
DISPLAY 0.978723 (-2325 -375);
PAINT WHITE (-2325 -375);
DISPLAY INVISIBLE (-2325 -375);
FORCEPROP 1 LAST LOCATION PR299
J 0
(-2325 -375);
DISPLAY 1.021277 (-2325 -375);
PAINT AQUA (-2325 -375);
DISPLAY INVISIBLE (-2325 -375);
FORCEPROP 0 LAST $SEC 1
J 0
(-2325 -375);
DISPLAY 0.680851 (-2325 -375);
PAINT MONO (-2325 -375);
DISPLAY INVISIBLE (-2325 -375);
FORCEPROP 0 LAST CDS_SEC 1
J 0
(-2325 -375);
DISPLAY 1.021277 (-2325 -375);
DISPLAY INVISIBLE (-2325 -375);
FORCEADD VCC15..1
(-2375 -225);
FORCEPROP 3 LASTPIN (-2375 -275) SIG_NAME PVCCIN_CPU1_PVCC\g
J 0
(-2365 -265);
DISPLAY 0.659574 (-2365 -265);
PAINT MONO (-2365 -265);
DISPLAY INVISIBLE (-2365 -265);
FORCEPROP 1 LAST HDL_POWER PVCCIN_CPU1_PVCC
J 1
(-2375 -175);
DISPLAY 0.617021 (-2375 -175);
PAINT GREEN (-2375 -175);
FORCEPROP 2 LAST CDS_LIB logical_power
J 0
(-2375 -225);
DISPLAY INVISIBLE (-2375 -225);
FORCEPROP 1 LAST PATH I13
J 0
(-2325 -200);
DISPLAY 0.872340 (-2325 -200);
PAINT AQUA (-2325 -200);
DISPLAY INVISIBLE (-2325 -200);
FORCEADD UNIVERSAL_GND..1
(-2750 550);
FORCEPROP 3 LASTPIN (-2750 600) SIG_NAME GND\g
J 0
(-2740 610);
DISPLAY 0.659574 (-2740 610);
PAINT MONO (-2740 610);
DISPLAY INVISIBLE (-2740 610);
FORCEPROP 1 LAST HDL_POWER GND
J 1
(-2725 475);
DISPLAY 0.872340 (-2725 475);
PAINT GREEN (-2725 475);
DISPLAY INVISIBLE (-2725 475);
FORCEPROP 2 LAST CDS_LIB logical_power
J 0
(-2750 550);
PAINT MONO (-2750 550);
DISPLAY INVISIBLE (-2750 550);
FORCEPROP 1 LAST PATH I14
J 0
(-2675 550);
DISPLAY 0.872340 (-2675 550);
PAINT AQUA (-2675 550);
DISPLAY INVISIBLE (-2675 550);
FORCEADD Q_RES..2
R 2
(-2750 775);
FORCEPROP 1 LAST PART_NUMBER CS28872FB01
J 2
(-2800 650);
DISPLAY 0.617021 (-2800 650);
PAINT BLUE (-2800 650);
DISPLAY INVISIBLE (-2800 650);
FORCEPROP 1 LAST WATTAGE 1/16W
J 2
(-2800 750);
DISPLAY 0.617021 (-2800 750);
PAINT SKYBLUE (-2800 750);
FORCEPROP 1 LAST PACK_TYPE 0402LF
J 2
(-2800 600);
DISPLAY 0.617021 (-2800 600);
PAINT SKYBLUE (-2800 600);
FORCEPROP 1 LAST VALUE 8.87K
J 2
(-2805 850);
DISPLAY 0.617021 (-2805 850);
PAINT SKYBLUE (-2805 850);
FORCEPROP 1 LAST TOLERANCE 1%
J 2
(-2805 800);
DISPLAY 0.617021 (-2805 800);
PAINT SKYBLUE (-2805 800);
FORCEPROP 1 LAST MATERIAL EMPTY
J 2
(-2800 700);
DISPLAY 0.617021 (-2800 700);
PAINT RED (-2800 700);
FORCEPROP 1 LAST LOCATION PR298
J 2
(-2795 900);
DISPLAY 0.617021 (-2795 900);
PAINT AQUA (-2795 900);
FORCEPROP 1 LASTPIN (-2750 875) $PN 1
J 2
(-2755 837);
DISPLAY 0.617021 (-2755 837);
PAINT MONO (-2755 837);
FORCEPROP 1 LASTPIN (-2750 675) $PN 2
J 2
(-2755 685);
DISPLAY 0.617021 (-2755 685);
PAINT MONO (-2755 685);
FORCEPROP 2 LAST CDS_LIB pure_quanta
J 2
(-2750 775);
DISPLAY INVISIBLE (-2750 775);
FORCEPROP 1 LAST PATH I15
J 2
(-2800 950);
DISPLAY 0.978723 (-2800 950);
PAINT WHITE (-2800 950);
DISPLAY INVISIBLE (-2800 950);
FORCEPROP 1 LAST LOCATION PR298
J 2
(-2800 950);
DISPLAY 1.021277 (-2800 950);
PAINT AQUA (-2800 950);
DISPLAY INVISIBLE (-2800 950);
FORCEPROP 0 LAST $SEC 1
J 2
(-2800 950);
DISPLAY 0.680851 (-2800 950);
PAINT MONO (-2800 950);
DISPLAY INVISIBLE (-2800 950);
FORCEPROP 0 LAST CDS_SEC 1
J 2
(-2800 950);
DISPLAY 1.021277 (-2800 950);
DISPLAY INVISIBLE (-2800 950);
FORCEADD OFFPAGE..5
(-2275 775);
FORCEPROP 2 LAST $XR4 284 
J 0
(-2530 847);
DISPLAY 0.638298 (-2530 847);
PAINT MONO (-2530 847);
FORCEPROP 2 LAST $XR3 288 
J 0
(-2530 703);
DISPLAY 0.638298 (-2530 703);
PAINT MONO (-2530 703);
FORCEPROP 2 LAST $XR2 287 
J 0
(-2530 811);
DISPLAY 0.638298 (-2530 811);
PAINT MONO (-2530 811);
FORCEPROP 2 LAST $XR1 286 
J 0
(-2530 739);
DISPLAY 0.638298 (-2530 739);
PAINT MONO (-2530 739);
FORCEPROP 2 LAST $XR0 285 
J 0
(-2530 775);
DISPLAY 0.638298 (-2530 775);
PAINT MONO (-2530 775);
FORCEPROP 1 LAST COMMENT_BODY TRUE
J 0
(-2175 700);
DISPLAY 0.872340 (-2175 700);
PAINT GREEN (-2175 700);
DISPLAY INVISIBLE (-2175 700);
FORCEPROP 1 LAST OFFPAGE TRUE
J 0
(-1950 650);
DISPLAY 0.872340 (-1950 650);
PAINT GREEN (-1950 650);
DISPLAY INVISIBLE (-1950 650);
FORCEPROP 2 LAST CDS_LIB standard
J 0
(-2275 775);
DISPLAY INVISIBLE (-2275 775);
FORCEPROP 2 LAST PATH I16
J 0
(-2525 900);
DISPLAY 1.021277 (-2525 900);
DISPLAY INVISIBLE (-2525 900);
FORCEADD OFFPAGE..1
(-2275 675);
FORCEPROP 2 LAST $XR0 284 
J 0
(-2701 675);
DISPLAY 0.638298 (-2701 675);
PAINT MONO (-2701 675);
FORCEPROP 1 LAST COMMENT_BODY TRUE
J 0
(-2150 575);
DISPLAY 0.872340 (-2150 575);
PAINT GREEN (-2150 575);
DISPLAY INVISIBLE (-2150 575);
FORCEPROP 1 LAST OFFPAGE TRUE
J 0
(-1950 550);
DISPLAY 0.872340 (-1950 550);
PAINT GREEN (-1950 550);
DISPLAY INVISIBLE (-1950 550);
FORCEPROP 2 LAST CDS_LIB standard
J 0
(-2275 675);
DISPLAY INVISIBLE (-2275 675);
FORCEPROP 2 LAST PATH I17
J 0
(-2700 725);
DISPLAY 1.021277 (-2700 725);
DISPLAY INVISIBLE (-2700 725);
FORCEADD UNIVERSAL_GND..1
(-1950 -775);
FORCEPROP 3 LASTPIN (-1950 -725) SIG_NAME GND\g
J 0
(-1940 -715);
DISPLAY 0.659574 (-1940 -715);
PAINT MONO (-1940 -715);
DISPLAY INVISIBLE (-1940 -715);
FORCEPROP 1 LAST HDL_POWER GND
J 1
(-1925 -850);
DISPLAY 0.872340 (-1925 -850);
PAINT GREEN (-1925 -850);
DISPLAY INVISIBLE (-1925 -850);
FORCEPROP 2 LAST CDS_LIB logical_power
J 0
(-1950 -775);
PAINT MONO (-1950 -775);
DISPLAY INVISIBLE (-1950 -775);
FORCEPROP 1 LAST PATH I18
J 0
(-1875 -775);
DISPLAY 0.872340 (-1875 -775);
PAINT AQUA (-1875 -775);
DISPLAY INVISIBLE (-1875 -775);
FORCEADD Q_CAP..1
(-1950 -550);
FORCEPROP 1 LAST PART_NUMBER CH5222KEB01
J 0
(-1900 -675);
DISPLAY 0.617021 (-1900 -675);
PAINT BLUE (-1900 -675);
DISPLAY INVISIBLE (-1900 -675);
FORCEPROP 1 LAST PACK_TYPE C0402
J 0
(-1900 -725);
DISPLAY 0.617021 (-1900 -725);
PAINT SKYBLUE (-1900 -725);
FORCEPROP 1 LAST VOLTAGE 10V
J 0
(-1900 -525);
DISPLAY 0.617021 (-1900 -525);
PAINT SKYBLUE (-1900 -525);
FORCEPROP 1 LAST VALUE 2.2UF
J 0
(-1900 -475);
DISPLAY 0.617021 (-1900 -475);
PAINT SKYBLUE (-1900 -475);
FORCEPROP 1 LAST TOLERANCE 10%
J 0
(-1900 -575);
DISPLAY 0.617021 (-1900 -575);
PAINT SKYBLUE (-1900 -575);
FORCEPROP 1 LAST MATERIAL X6S
J 0
(-1900 -625);
DISPLAY 0.617021 (-1900 -625);
PAINT SKYBLUE (-1900 -625);
FORCEPROP 1 LAST LOCATION PC525_P1_4
J 0
(-1900 -425);
DISPLAY 0.617021 (-1900 -425);
PAINT AQUA (-1900 -425);
FORCEPROP 1 LASTPIN (-1950 -450) $PN 1
J 0
(-1940 -470);
DISPLAY 0.617021 (-1940 -470);
PAINT MONO (-1940 -470);
FORCEPROP 1 LASTPIN (-1950 -650) $PN 2
J 0
(-1940 -670);
DISPLAY 0.617021 (-1940 -670);
PAINT MONO (-1940 -670);
FORCEPROP 2 LAST CDS_LIB pure_quanta
J 0
(-1950 -550);
DISPLAY INVISIBLE (-1950 -550);
FORCEPROP 1 LAST PATH I19
J 0
(-1900 -400);
DISPLAY 0.978723 (-1900 -400);
PAINT WHITE (-1900 -400);
DISPLAY INVISIBLE (-1900 -400);
FORCEPROP 1 LAST LOCATION PC525_P1_4
J 0
(-1900 -375);
DISPLAY 1.021277 (-1900 -375);
PAINT AQUA (-1900 -375);
DISPLAY INVISIBLE (-1900 -375);
FORCEPROP 0 LAST $SEC 1
J 0
(-1900 -375);
DISPLAY 0.680851 (-1900 -375);
PAINT MONO (-1900 -375);
DISPLAY INVISIBLE (-1900 -375);
FORCEPROP 0 LAST CDS_SEC 1
J 0
(-1900 -375);
DISPLAY 1.021277 (-1900 -375);
DISPLAY INVISIBLE (-1900 -375);
FORCEADD UNIVERSAL_GND..1
(-2875 -1825);
FORCEPROP 3 LASTPIN (-2875 -1775) SIG_NAME GND\g
J 0
(-2865 -1765);
DISPLAY 0.659574 (-2865 -1765);
PAINT MONO (-2865 -1765);
DISPLAY INVISIBLE (-2865 -1765);
FORCEPROP 1 LAST HDL_POWER GND
J 1
(-2850 -1900);
DISPLAY 0.872340 (-2850 -1900);
PAINT GREEN (-2850 -1900);
DISPLAY INVISIBLE (-2850 -1900);
FORCEPROP 2 LAST CDS_LIB logical_power
J 0
(-2875 -1825);
PAINT MONO (-2875 -1825);
DISPLAY INVISIBLE (-2875 -1825);
FORCEPROP 1 LAST PATH I2
J 0
(-2800 -1825);
DISPLAY 0.872340 (-2800 -1825);
PAINT AQUA (-2800 -1825);
DISPLAY INVISIBLE (-2800 -1825);
FORCEADD UNIVERSAL_GND..1
(-2850 1000);
FORCEPROP 3 LASTPIN (-2850 1050) SIG_NAME GND\g
J 0
(-2840 1060);
DISPLAY 0.659574 (-2840 1060);
PAINT MONO (-2840 1060);
DISPLAY INVISIBLE (-2840 1060);
FORCEPROP 1 LAST HDL_POWER GND
J 1
(-2825 925);
DISPLAY 0.872340 (-2825 925);
PAINT GREEN (-2825 925);
DISPLAY INVISIBLE (-2825 925);
FORCEPROP 2 LAST CDS_LIB logical_power
J 0
(-2850 1000);
PAINT MONO (-2850 1000);
DISPLAY INVISIBLE (-2850 1000);
FORCEPROP 1 LAST PATH I20
J 0
(-2775 1000);
DISPLAY 0.872340 (-2775 1000);
PAINT AQUA (-2775 1000);
DISPLAY INVISIBLE (-2775 1000);
FORCEADD OFFPAGE..1
(-2275 1175);
FORCEPROP 2 LAST $XR6 290 
J 0
(-3277 1175);
DISPLAY 0.638298 (-3277 1175);
PAINT MONO (-3277 1175);
FORCEPROP 2 LAST $XR5 289 
J 0
(-3157 1175);
DISPLAY 0.638298 (-3157 1175);
PAINT MONO (-3157 1175);
FORCEPROP 2 LAST $XR4 288 
J 0
(-3037 1175);
DISPLAY 0.638298 (-3037 1175);
PAINT MONO (-3037 1175);
FORCEPROP 2 LAST $XR3 287 
J 0
(-2917 1175);
DISPLAY 0.638298 (-2917 1175);
PAINT MONO (-2917 1175);
FORCEPROP 2 LAST $XR2 286 
J 0
(-2797 1175);
DISPLAY 0.638298 (-2797 1175);
PAINT MONO (-2797 1175);
FORCEPROP 2 LAST $XR1 285 
J 0
(-2677 1175);
DISPLAY 0.638298 (-2677 1175);
PAINT MONO (-2677 1175);
FORCEPROP 2 LAST $XR0 284 
J 0
(-2557 1175);
DISPLAY 0.638298 (-2557 1175);
PAINT MONO (-2557 1175);
FORCEPROP 1 LAST COMMENT_BODY TRUE
J 0
(-2150 1075);
DISPLAY 0.872340 (-2150 1075);
PAINT GREEN (-2150 1075);
DISPLAY INVISIBLE (-2150 1075);
FORCEPROP 1 LAST OFFPAGE TRUE
J 0
(-1950 1050);
DISPLAY 0.872340 (-1950 1050);
PAINT GREEN (-1950 1050);
DISPLAY INVISIBLE (-1950 1050);
FORCEPROP 2 LAST CDS_LIB standard
J 0
(-2275 1175);
DISPLAY INVISIBLE (-2275 1175);
FORCEPROP 2 LAST PATH I21
J 0
(-2550 1225);
DISPLAY 1.021277 (-2550 1225);
DISPLAY INVISIBLE (-2550 1225);
FORCEADD OFFPAGE..5
(-2275 1275);
FORCEPROP 2 LAST $XR0 284 
J 0
(-2530 1275);
DISPLAY 0.638298 (-2530 1275);
PAINT MONO (-2530 1275);
FORCEPROP 1 LAST COMMENT_BODY TRUE
J 0
(-2175 1200);
DISPLAY 0.872340 (-2175 1200);
PAINT GREEN (-2175 1200);
DISPLAY INVISIBLE (-2175 1200);
FORCEPROP 1 LAST OFFPAGE TRUE
J 0
(-1950 1150);
DISPLAY 0.872340 (-1950 1150);
PAINT GREEN (-1950 1150);
DISPLAY INVISIBLE (-1950 1150);
FORCEPROP 2 LAST CDS_LIB standard
J 0
(-2275 1275);
DISPLAY INVISIBLE (-2275 1275);
FORCEPROP 2 LAST PATH I22
J 0
(-2525 1325);
DISPLAY 1.021277 (-2525 1325);
DISPLAY INVISIBLE (-2525 1325);
FORCEADD UNIVERSAL_GND..1
(-2350 1525);
FORCEPROP 3 LASTPIN (-2350 1575) SIG_NAME GND\g
J 0
(-2340 1585);
DISPLAY 0.659574 (-2340 1585);
PAINT MONO (-2340 1585);
DISPLAY INVISIBLE (-2340 1585);
FORCEPROP 1 LAST HDL_POWER GND
J 1
(-2325 1450);
DISPLAY 0.872340 (-2325 1450);
PAINT GREEN (-2325 1450);
DISPLAY INVISIBLE (-2325 1450);
FORCEPROP 2 LAST CDS_LIB logical_power
J 0
(-2350 1525);
PAINT MONO (-2350 1525);
DISPLAY INVISIBLE (-2350 1525);
FORCEPROP 1 LAST PATH I23
J 0
(-2275 1525);
DISPLAY 0.872340 (-2275 1525);
PAINT AQUA (-2275 1525);
DISPLAY INVISIBLE (-2275 1525);
FORCEADD Q_CAP..1
(-2350 1775);
FORCEPROP 1 LAST PART_NUMBER CH5222KEB01
J 0
(-2300 1600);
DISPLAY 0.617021 (-2300 1600);
PAINT BLUE (-2300 1600);
DISPLAY INVISIBLE (-2300 1600);
FORCEPROP 1 LAST PACK_TYPE C0402
J 0
(-2300 1650);
DISPLAY 0.617021 (-2300 1650);
PAINT SKYBLUE (-2300 1650);
FORCEPROP 1 LAST VOLTAGE 10V
J 0
(-2300 1800);
DISPLAY 0.617021 (-2300 1800);
PAINT SKYBLUE (-2300 1800);
FORCEPROP 1 LAST VALUE 2.2UF
J 0
(-2300 1850);
DISPLAY 0.617021 (-2300 1850);
PAINT SKYBLUE (-2300 1850);
FORCEPROP 1 LAST TOLERANCE 10%
J 0
(-2300 1750);
DISPLAY 0.617021 (-2300 1750);
PAINT SKYBLUE (-2300 1750);
FORCEPROP 1 LAST MATERIAL X6S
J 0
(-2300 1700);
DISPLAY 0.617021 (-2300 1700);
PAINT SKYBLUE (-2300 1700);
FORCEPROP 1 LAST LOCATION PC524
J 0
(-2300 1900);
DISPLAY 0.617021 (-2300 1900);
PAINT AQUA (-2300 1900);
FORCEPROP 1 LASTPIN (-2350 1875) $PN 1
J 0
(-2340 1855);
DISPLAY 0.617021 (-2340 1855);
PAINT MONO (-2340 1855);
FORCEPROP 1 LASTPIN (-2350 1675) $PN 2
J 0
(-2340 1655);
DISPLAY 0.617021 (-2340 1655);
PAINT MONO (-2340 1655);
FORCEPROP 2 LAST CDS_LIB pure_quanta
J 0
(-2350 1775);
DISPLAY INVISIBLE (-2350 1775);
FORCEPROP 1 LAST PATH I24
J 0
(-2300 1925);
DISPLAY 0.978723 (-2300 1925);
PAINT WHITE (-2300 1925);
DISPLAY INVISIBLE (-2300 1925);
FORCEPROP 1 LAST LOCATION PC524
J 0
(-2300 1950);
DISPLAY 1.021277 (-2300 1950);
PAINT AQUA (-2300 1950);
DISPLAY INVISIBLE (-2300 1950);
FORCEPROP 0 LAST $SEC 1
J 0
(-2300 1950);
DISPLAY 0.680851 (-2300 1950);
PAINT MONO (-2300 1950);
DISPLAY INVISIBLE (-2300 1950);
FORCEPROP 0 LAST CDS_SEC 1
J 0
(-2300 1950);
DISPLAY 1.021277 (-2300 1950);
DISPLAY INVISIBLE (-2300 1950);
FORCEADD Q_RES..2
(-2350 2275);
FORCEPROP 1 LAST PART_NUMBER CS-2202FB01
J 0
(-2310 2150);
DISPLAY 0.617021 (-2310 2150);
PAINT BLUE (-2310 2150);
DISPLAY INVISIBLE (-2310 2150);
FORCEPROP 1 LAST WATTAGE 1/16W
J 0
(-2310 2250);
DISPLAY 0.617021 (-2310 2250);
PAINT SKYBLUE (-2310 2250);
FORCEPROP 1 LAST PACK_TYPE 0402LF
J 0
(-2310 2100);
DISPLAY 0.617021 (-2310 2100);
PAINT SKYBLUE (-2310 2100);
FORCEPROP 1 LAST VALUE 2.2
J 0
(-2305 2350);
DISPLAY 0.617021 (-2305 2350);
PAINT SKYBLUE (-2305 2350);
FORCEPROP 1 LAST TOLERANCE 1%
J 0
(-2305 2300);
DISPLAY 0.617021 (-2305 2300);
PAINT SKYBLUE (-2305 2300);
FORCEPROP 1 LAST MATERIAL CHIP
J 0
(-2310 2200);
DISPLAY 0.617021 (-2310 2200);
PAINT SKYBLUE (-2310 2200);
FORCEPROP 1 LAST LOCATION PR300
J 0
(-2305 2400);
DISPLAY 0.617021 (-2305 2400);
PAINT AQUA (-2305 2400);
FORCEPROP 1 LASTPIN (-2350 2375) $PN 1
J 0
(-2345 2337);
DISPLAY 0.617021 (-2345 2337);
PAINT MONO (-2345 2337);
FORCEPROP 1 LASTPIN (-2350 2175) $PN 2
J 0
(-2345 2185);
DISPLAY 0.617021 (-2345 2185);
PAINT MONO (-2345 2185);
FORCEPROP 2 LAST CDS_LIB pure_quanta
J 0
(-2350 2275);
DISPLAY INVISIBLE (-2350 2275);
FORCEPROP 1 LAST PATH I25
J 0
(-2300 2450);
DISPLAY 0.978723 (-2300 2450);
PAINT WHITE (-2300 2450);
DISPLAY INVISIBLE (-2300 2450);
FORCEPROP 1 LAST LOCATION PR300
J 0
(-2300 2450);
DISPLAY 1.021277 (-2300 2450);
PAINT AQUA (-2300 2450);
DISPLAY INVISIBLE (-2300 2450);
FORCEPROP 0 LAST $SEC 1
J 0
(-2300 2450);
DISPLAY 0.680851 (-2300 2450);
PAINT MONO (-2300 2450);
DISPLAY INVISIBLE (-2300 2450);
FORCEPROP 0 LAST CDS_SEC 1
J 0
(-2300 2450);
DISPLAY 1.021277 (-2300 2450);
DISPLAY INVISIBLE (-2300 2450);
FORCEADD VCC15..1
(-2350 2600);
FORCEPROP 3 LASTPIN (-2350 2550) SIG_NAME PVCCIN_CPU1_PVCC\g
J 0
(-2340 2560);
DISPLAY 0.659574 (-2340 2560);
PAINT MONO (-2340 2560);
DISPLAY INVISIBLE (-2340 2560);
FORCEPROP 1 LAST HDL_POWER PVCCIN_CPU1_PVCC
J 1
(-2350 2650);
DISPLAY 0.617021 (-2350 2650);
PAINT GREEN (-2350 2650);
FORCEPROP 2 LAST CDS_LIB logical_power
J 0
(-2350 2600);
DISPLAY INVISIBLE (-2350 2600);
FORCEPROP 1 LAST PATH I26
J 0
(-2300 2625);
DISPLAY 0.872340 (-2300 2625);
PAINT AQUA (-2300 2625);
DISPLAY INVISIBLE (-2300 2625);
FORCEADD Q_CAP..2
(-2025 1075);
FORCEPROP 1 LAST PART_NUMBER CH4104K1B00
J 1
(-1800 1100);
DISPLAY 0.617021 (-1800 1100);
PAINT BLUE (-1800 1100);
DISPLAY INVISIBLE (-1800 1100);
FORCEPROP 1 LAST PACK_TYPE 0402
J 1
(-1650 1075);
DISPLAY 0.617021 (-1650 1075);
PAINT SKYBLUE (-1650 1075);
FORCEPROP 1 LAST VOLTAGE 25V
J 0
(-1775 1075);
DISPLAY 0.617021 (-1775 1075);
PAINT SKYBLUE (-1775 1075);
FORCEPROP 1 LAST VALUE 0.1UF
J 2
(-1800 1075);
DISPLAY 0.617021 (-1800 1075);
PAINT SKYBLUE (-1800 1075);
FORCEPROP 1 LAST TOLERANCE 10%
J 2
(-1500 1100);
DISPLAY 0.617021 (-1500 1100);
PAINT SKYBLUE (-1500 1100);
FORCEPROP 1 LAST MATERIAL X7R
J 0
(-1650 1100);
DISPLAY 0.617021 (-1650 1100);
PAINT SKYBLUE (-1650 1100);
FORCEPROP 1 LAST LOCATION PC1359
J 1
(-2225 1075);
DISPLAY 0.617021 (-2225 1075);
PAINT AQUA (-2225 1075);
FORCEPROP 1 LASTPIN (-2125 1075) $PN 1
J 0
(-2135 1090);
DISPLAY 0.617021 (-2135 1090);
FORCEPROP 1 LASTPIN (-1925 1075) $PN 2
J 0
(-1940 1090);
DISPLAY 0.617021 (-1940 1090);
FORCEPROP 2 LAST CDS_LIB pure_quanta
J 0
(-2025 1075);
PAINT MONO (-2025 1075);
DISPLAY INVISIBLE (-2025 1075);
FORCEPROP 1 LAST PATH I27
J 0
(-2025 1275);
DISPLAY 0.978723 (-2025 1275);
PAINT WHITE (-2025 1275);
DISPLAY INVISIBLE (-2025 1275);
FORCEPROP 2 LAST $SEC 1
J 0
(-2025 1325);
DISPLAY 0.680851 (-2025 1325);
PAINT MONO (-2025 1325);
DISPLAY INVISIBLE (-2025 1325);
FORCEPROP 2 LAST CDS_SEC 1
J 0
(-2025 1325);
DISPLAY 1.021277 (-2025 1325);
DISPLAY INVISIBLE (-2025 1325);
FORCEADD UNIVERSAL_GND..1
(-1925 2050);
FORCEPROP 3 LASTPIN (-1925 2100) SIG_NAME GND\g
J 0
(-1915 2110);
DISPLAY 0.659574 (-1915 2110);
PAINT MONO (-1915 2110);
DISPLAY INVISIBLE (-1915 2110);
FORCEPROP 1 LAST HDL_POWER GND
J 1
(-1900 1975);
DISPLAY 0.872340 (-1900 1975);
PAINT GREEN (-1900 1975);
DISPLAY INVISIBLE (-1900 1975);
FORCEPROP 2 LAST CDS_LIB logical_power
J 0
(-1925 2050);
PAINT MONO (-1925 2050);
DISPLAY INVISIBLE (-1925 2050);
FORCEPROP 1 LAST PATH I28
J 0
(-1850 2050);
DISPLAY 0.872340 (-1850 2050);
PAINT AQUA (-1850 2050);
DISPLAY INVISIBLE (-1850 2050);
FORCEADD Q_CAP..1
(-1925 2275);
FORCEPROP 1 LAST PART_NUMBER CH5222KEB01
J 0
(-1875 2150);
DISPLAY 0.617021 (-1875 2150);
PAINT BLUE (-1875 2150);
DISPLAY INVISIBLE (-1875 2150);
FORCEPROP 1 LAST VOLTAGE 10V
J 0
(-1875 2300);
DISPLAY 0.617021 (-1875 2300);
PAINT SKYBLUE (-1875 2300);
FORCEPROP 1 LAST PACK_TYPE C0402
J 0
(-1875 2100);
DISPLAY 0.617021 (-1875 2100);
PAINT SKYBLUE (-1875 2100);
FORCEPROP 1 LAST VALUE 2.2UF
J 0
(-1875 2350);
DISPLAY 0.617021 (-1875 2350);
PAINT SKYBLUE (-1875 2350);
FORCEPROP 1 LAST TOLERANCE 10%
J 0
(-1875 2250);
DISPLAY 0.617021 (-1875 2250);
PAINT SKYBLUE (-1875 2250);
FORCEPROP 1 LAST MATERIAL X6S
J 0
(-1875 2200);
DISPLAY 0.617021 (-1875 2200);
PAINT SKYBLUE (-1875 2200);
FORCEPROP 1 LAST LOCATION PC526_P1_3
J 0
(-1875 2400);
DISPLAY 0.617021 (-1875 2400);
PAINT AQUA (-1875 2400);
FORCEPROP 1 LASTPIN (-1925 2375) $PN 1
J 0
(-1915 2355);
DISPLAY 0.617021 (-1915 2355);
PAINT MONO (-1915 2355);
FORCEPROP 1 LASTPIN (-1925 2175) $PN 2
J 0
(-1915 2155);
DISPLAY 0.617021 (-1915 2155);
PAINT MONO (-1915 2155);
FORCEPROP 2 LAST CDS_LIB pure_quanta
J 0
(-1925 2275);
DISPLAY INVISIBLE (-1925 2275);
FORCEPROP 1 LAST PATH I29
J 0
(-1875 2425);
DISPLAY 0.978723 (-1875 2425);
PAINT WHITE (-1875 2425);
DISPLAY INVISIBLE (-1875 2425);
FORCEPROP 1 LAST LOCATION PC526_P1_3
J 0
(-1875 2450);
DISPLAY 1.021277 (-1875 2450);
PAINT AQUA (-1875 2450);
DISPLAY INVISIBLE (-1875 2450);
FORCEPROP 0 LAST $SEC 1
J 0
(-1875 2450);
DISPLAY 0.680851 (-1875 2450);
PAINT MONO (-1875 2450);
DISPLAY INVISIBLE (-1875 2450);
FORCEPROP 0 LAST CDS_SEC 1
J 0
(-1875 2450);
DISPLAY 1.021277 (-1875 2450);
DISPLAY INVISIBLE (-1875 2450);
FORCEADD Q_RES..2
R 2
(-2775 -2050);
FORCEPROP 1 LAST PART_NUMBER CS28872FB01
J 2
(-2825 -2175);
DISPLAY 0.617021 (-2825 -2175);
PAINT BLUE (-2825 -2175);
DISPLAY INVISIBLE (-2825 -2175);
FORCEPROP 1 LAST PACK_TYPE 0402LF
J 2
(-2825 -2225);
DISPLAY 0.617021 (-2825 -2225);
PAINT SKYBLUE (-2825 -2225);
FORCEPROP 1 LAST VALUE 8.87K
J 2
(-2830 -1975);
DISPLAY 0.617021 (-2830 -1975);
PAINT SKYBLUE (-2830 -1975);
FORCEPROP 1 LAST TOLERANCE 1%
J 2
(-2830 -2025);
DISPLAY 0.617021 (-2830 -2025);
PAINT SKYBLUE (-2830 -2025);
FORCEPROP 1 LAST MATERIAL EMPTY
J 2
(-2825 -2125);
DISPLAY 0.617021 (-2825 -2125);
PAINT RED (-2825 -2125);
FORCEPROP 1 LAST WATTAGE 1/16W
J 2
(-2825 -2075);
DISPLAY 0.617021 (-2825 -2075);
PAINT SKYBLUE (-2825 -2075);
FORCEPROP 1 LAST LOCATION PR297
J 2
(-2820 -1925);
DISPLAY 0.617021 (-2820 -1925);
PAINT AQUA (-2820 -1925);
FORCEPROP 1 LASTPIN (-2775 -1950) $PN 1
J 2
(-2780 -1988);
DISPLAY 0.617021 (-2780 -1988);
PAINT MONO (-2780 -1988);
FORCEPROP 1 LASTPIN (-2775 -2150) $PN 2
J 2
(-2780 -2140);
DISPLAY 0.617021 (-2780 -2140);
PAINT MONO (-2780 -2140);
FORCEPROP 2 LAST CDS_LIB pure_quanta
J 2
(-2775 -2050);
DISPLAY INVISIBLE (-2775 -2050);
FORCEPROP 1 LAST PATH I3
J 2
(-2825 -1875);
DISPLAY 0.978723 (-2825 -1875);
PAINT WHITE (-2825 -1875);
DISPLAY INVISIBLE (-2825 -1875);
FORCEPROP 1 LAST LOCATION PR297
J 2
(-2825 -1875);
DISPLAY 1.021277 (-2825 -1875);
PAINT AQUA (-2825 -1875);
DISPLAY INVISIBLE (-2825 -1875);
FORCEPROP 0 LAST $SEC 1
J 2
(-2825 -1875);
DISPLAY 0.680851 (-2825 -1875);
PAINT MONO (-2825 -1875);
DISPLAY INVISIBLE (-2825 -1875);
FORCEPROP 0 LAST CDS_SEC 1
J 2
(-2825 -1875);
DISPLAY 1.021277 (-2825 -1875);
DISPLAY INVISIBLE (-2825 -1875);
FORCEADD UNIVERSAL_GND..1
(-200 -2275);
FORCEPROP 3 LASTPIN (-200 -2225) SIG_NAME GND\g
J 0
(-190 -2215);
DISPLAY 0.659574 (-190 -2215);
PAINT MONO (-190 -2215);
DISPLAY INVISIBLE (-190 -2215);
FORCEPROP 1 LAST HDL_POWER GND
J 1
(-175 -2350);
DISPLAY 0.872340 (-175 -2350);
PAINT GREEN (-175 -2350);
DISPLAY INVISIBLE (-175 -2350);
FORCEPROP 2 LAST CDS_LIB logical_power
J 0
(-200 -2275);
PAINT MONO (-200 -2275);
DISPLAY INVISIBLE (-200 -2275);
FORCEPROP 1 LAST PATH I30
J 0
(-125 -2275);
DISPLAY 0.872340 (-125 -2275);
PAINT AQUA (-125 -2275);
DISPLAY INVISIBLE (-125 -2275);
FORCEADD OFFPAGE..6
(350 -1800);
FORCEPROP 2 LAST $XR0 287 
J 0
(70 -1800);
DISPLAY 0.638298 (70 -1800);
PAINT MONO (70 -1800);
FORCEPROP 2 LAST CDS_LIB standard
J 0
(350 -1800);
DISPLAY INVISIBLE (350 -1800);
FORCEPROP 1 LAST OFFPAGE TRUE
J 0
(675 -1925);
DISPLAY 0.872340 (675 -1925);
PAINT GREEN (675 -1925);
DISPLAY INVISIBLE (675 -1925);
FORCEPROP 1 LAST COMMENT_BODY TRUE
J 0
(450 -1875);
DISPLAY 0.872340 (450 -1875);
PAINT GREEN (450 -1875);
DISPLAY INVISIBLE (450 -1875);
FORCEPROP 2 LAST PATH I31
J 0
(75 -1750);
DISPLAY 1.021277 (75 -1750);
DISPLAY INVISIBLE (75 -1750);
FORCEADD UNIVERSAL_GND..1
(-175 550);
FORCEPROP 3 LASTPIN (-175 600) SIG_NAME GND\g
J 0
(-165 610);
DISPLAY 0.659574 (-165 610);
PAINT MONO (-165 610);
DISPLAY INVISIBLE (-165 610);
FORCEPROP 1 LAST HDL_POWER GND
J 1
(-150 475);
DISPLAY 0.872340 (-150 475);
PAINT GREEN (-150 475);
DISPLAY INVISIBLE (-150 475);
FORCEPROP 2 LAST CDS_LIB logical_power
J 0
(-175 550);
PAINT MONO (-175 550);
DISPLAY INVISIBLE (-175 550);
FORCEPROP 1 LAST PATH I32
J 0
(-100 550);
DISPLAY 0.872340 (-100 550);
PAINT AQUA (-100 550);
DISPLAY INVISIBLE (-100 550);
FORCEADD Q_CAP..1
(-50 -650);
FORCEPROP 1 LAST PART_NUMBER TMP_QCH2336K1B12
J 0
(0 -800);
DISPLAY 0.617021 (0 -800);
PAINT BLUE (0 -800);
DISPLAY INVISIBLE (0 -800);
FORCEPROP 1 LAST VOLTAGE 50V
J 0
(0 -600);
DISPLAY 0.617021 (0 -600);
PAINT SKYBLUE (0 -600);
FORCEPROP 1 LAST VALUE 3300PF
J 0
(0 -550);
DISPLAY 0.617021 (0 -550);
PAINT SKYBLUE (0 -550);
FORCEPROP 1 LAST TOLERANCE 10%
J 0
(0 -650);
DISPLAY 0.617021 (0 -650);
PAINT SKYBLUE (0 -650);
FORCEPROP 1 LAST MATERIAL X7R
J 0
(0 -700);
DISPLAY 0.617021 (0 -700);
PAINT SKYBLUE (0 -700);
FORCEPROP 1 LAST PACK_TYPE 0402
J 0
(0 -750);
DISPLAY 0.617021 (0 -750);
PAINT SKYBLUE (0 -750);
FORCEPROP 1 LAST LOCATION PC527_P1_4
J 0
(0 -500);
DISPLAY 0.617021 (0 -500);
PAINT AQUA (0 -500);
FORCEPROP 1 LASTPIN (-50 -550) $PN 1
J 0
(-40 -570);
DISPLAY 0.617021 (-40 -570);
PAINT MONO (-40 -570);
FORCEPROP 1 LASTPIN (-50 -750) $PN 2
J 0
(-40 -770);
DISPLAY 0.617021 (-40 -770);
PAINT MONO (-40 -770);
FORCEPROP 2 LAST CDS_LIB pure_quanta
J 0
(-50 -650);
DISPLAY INVISIBLE (-50 -650);
FORCEPROP 1 LAST PATH I33
J 0
(0 -500);
DISPLAY 0.978723 (0 -500);
PAINT WHITE (0 -500);
DISPLAY INVISIBLE (0 -500);
FORCEPROP 1 LAST LOCATION PC527_P1_4
J 0
(0 -450);
DISPLAY 1.021277 (0 -450);
PAINT AQUA (0 -450);
DISPLAY INVISIBLE (0 -450);
FORCEPROP 0 LAST $SEC 1
J 0
(0 -450);
DISPLAY 0.680851 (0 -450);
PAINT MONO (0 -450);
DISPLAY INVISIBLE (0 -450);
FORCEPROP 0 LAST CDS_SEC 1
J 0
(0 -450);
DISPLAY 1.021277 (0 -450);
DISPLAY INVISIBLE (0 -450);
FORCEADD Q_RES..1
(400 -1100);
FORCEPROP 1 LAST PART_NUMBER CS-3302FB01
J 0
(300 -1050);
DISPLAY 0.617021 (300 -1050);
PAINT BLUE (300 -1050);
DISPLAY INVISIBLE (300 -1050);
FORCEPROP 1 LAST PACK_TYPE 0402LF
J 0
(300 -1025);
DISPLAY 0.617021 (300 -1025);
PAINT SKYBLUE (300 -1025);
FORCEPROP 1 LAST VALUE 3.3
J 2
(525 -1100);
DISPLAY 0.617021 (525 -1100);
PAINT SKYBLUE (525 -1100);
FORCEPROP 1 LAST TOLERANCE 1%
J 0
(550 -1100);
DISPLAY 0.617021 (550 -1100);
PAINT SKYBLUE (550 -1100);
FORCEPROP 1 LAST MATERIAL CHIP
J 0
(300 -1000);
DISPLAY 0.617021 (300 -1000);
PAINT SKYBLUE (300 -1000);
FORCEPROP 1 LAST WATTAGE 1/16W
J 2
(525 -1025);
DISPLAY 0.617021 (525 -1025);
PAINT SKYBLUE (525 -1025);
FORCEPROP 1 LAST LOCATION PR1788
J 0
(200 -1100);
DISPLAY 0.617021 (200 -1100);
PAINT AQUA (200 -1100);
FORCEPROP 1 LASTPIN (300 -1100) $PN 1
J 0
(312 -1088);
DISPLAY 0.617021 (312 -1088);
FORCEPROP 1 LASTPIN (500 -1100) $PN 2
J 0
(462 -1088);
DISPLAY 0.617021 (462 -1088);
FORCEPROP 2 LAST CDS_LIB pure_quanta
J 0
(400 -1100);
PAINT MONO (400 -1100);
DISPLAY INVISIBLE (400 -1100);
FORCEPROP 1 LAST PATH I34
J 0
(350 -950);
DISPLAY 0.978723 (350 -950);
PAINT WHITE (350 -950);
DISPLAY INVISIBLE (350 -950);
FORCEPROP 2 LAST $SEC 1
J 0
(350 -900);
DISPLAY 0.680851 (350 -900);
PAINT MONO (350 -900);
DISPLAY INVISIBLE (350 -900);
FORCEPROP 2 LAST CDS_SEC 1
J 0
(350 -900);
DISPLAY 1.021277 (350 -900);
DISPLAY INVISIBLE (350 -900);
FORCEADD Q_CAP..1
(350 -650);
FORCEPROP 1 LAST PART_NUMBER CH5103KEB01
J 0
(400 -800);
DISPLAY 0.617021 (400 -800);
PAINT BLUE (400 -800);
DISPLAY INVISIBLE (400 -800);
FORCEPROP 1 LAST PACK_TYPE C0402
J 0
(400 -750);
DISPLAY 0.617021 (400 -750);
PAINT SKYBLUE (400 -750);
FORCEPROP 1 LAST VOLTAGE 16V
J 0
(400 -600);
DISPLAY 0.617021 (400 -600);
PAINT SKYBLUE (400 -600);
FORCEPROP 1 LAST VALUE 1UF
J 0
(400 -550);
DISPLAY 0.617021 (400 -550);
PAINT SKYBLUE (400 -550);
FORCEPROP 1 LAST TOLERANCE 10%
J 0
(400 -650);
DISPLAY 0.617021 (400 -650);
PAINT SKYBLUE (400 -650);
FORCEPROP 1 LAST MATERIAL X6S
J 0
(400 -700);
DISPLAY 0.617021 (400 -700);
PAINT SKYBLUE (400 -700);
FORCEPROP 1 LAST LOCATION PC529_P1_4
J 0
(400 -500);
DISPLAY 0.617021 (400 -500);
PAINT AQUA (400 -500);
FORCEPROP 1 LASTPIN (350 -550) $PN 1
J 0
(360 -570);
DISPLAY 0.617021 (360 -570);
PAINT MONO (360 -570);
FORCEPROP 1 LASTPIN (350 -750) $PN 2
J 0
(360 -770);
DISPLAY 0.617021 (360 -770);
PAINT MONO (360 -770);
FORCEPROP 2 LAST CDS_LIB pure_quanta
J 0
(350 -650);
DISPLAY INVISIBLE (350 -650);
FORCEPROP 1 LAST PATH I35
J 0
(400 -500);
DISPLAY 0.978723 (400 -500);
PAINT WHITE (400 -500);
DISPLAY INVISIBLE (400 -500);
FORCEPROP 1 LAST LOCATION PC529_P1_4
J 0
(400 -450);
DISPLAY 1.021277 (400 -450);
PAINT AQUA (400 -450);
DISPLAY INVISIBLE (400 -450);
FORCEPROP 0 LAST $SEC 1
J 0
(400 -450);
DISPLAY 0.680851 (400 -450);
PAINT MONO (400 -450);
DISPLAY INVISIBLE (400 -450);
FORCEPROP 0 LAST CDS_SEC 1
J 0
(400 -450);
DISPLAY 1.021277 (400 -450);
DISPLAY INVISIBLE (400 -450);
FORCEADD Q_CAP..1
(750 -650);
FORCEPROP 1 LAST PART_NUMBER CH6223MEA01
J 0
(800 -800);
DISPLAY 0.617021 (800 -800);
PAINT BLUE (800 -800);
DISPLAY INVISIBLE (800 -800);
FORCEPROP 1 LAST PACK_TYPE C0805
J 0
(800 -750);
DISPLAY 0.617021 (800 -750);
PAINT SKYBLUE (800 -750);
FORCEPROP 1 LAST VOLTAGE 16V
J 0
(800 -600);
DISPLAY 0.617021 (800 -600);
PAINT SKYBLUE (800 -600);
FORCEPROP 1 LAST VALUE 22UF
J 0
(800 -550);
DISPLAY 0.617021 (800 -550);
PAINT SKYBLUE (800 -550);
FORCEPROP 1 LAST TOLERANCE 20%
J 0
(800 -650);
DISPLAY 0.617021 (800 -650);
PAINT SKYBLUE (800 -650);
FORCEPROP 1 LAST MATERIAL X6S
J 0
(800 -700);
DISPLAY 0.617021 (800 -700);
PAINT SKYBLUE (800 -700);
FORCEPROP 1 LAST LOCATION PC533_P1_4
J 0
(800 -500);
DISPLAY 0.617021 (800 -500);
PAINT AQUA (800 -500);
FORCEPROP 1 LASTPIN (750 -550) $PN 1
J 0
(760 -570);
DISPLAY 0.617021 (760 -570);
PAINT MONO (760 -570);
FORCEPROP 1 LASTPIN (750 -750) $PN 2
J 0
(760 -770);
DISPLAY 0.617021 (760 -770);
PAINT MONO (760 -770);
FORCEPROP 2 LAST CDS_LIB pure_quanta
J 0
(750 -650);
DISPLAY INVISIBLE (750 -650);
FORCEPROP 1 LAST PATH I36
J 0
(800 -500);
DISPLAY 0.978723 (800 -500);
PAINT WHITE (800 -500);
DISPLAY INVISIBLE (800 -500);
FORCEPROP 1 LAST LOCATION PC533_P1_4
J 0
(800 -450);
DISPLAY 1.021277 (800 -450);
PAINT AQUA (800 -450);
DISPLAY INVISIBLE (800 -450);
FORCEPROP 0 LAST $SEC 1
J 0
(800 -450);
DISPLAY 0.680851 (800 -450);
PAINT MONO (800 -450);
DISPLAY INVISIBLE (800 -450);
FORCEPROP 0 LAST CDS_SEC 1
J 0
(800 -450);
DISPLAY 1.021277 (800 -450);
DISPLAY INVISIBLE (800 -450);
FORCEADD Q_INDUCTOR4P_14..1
(1600 -1675);
FORCEPROP 1 LAST PART_NUMBER CV+15^0TZ04
J 0
(1375 -1515);
DISPLAY 0.617021 (1375 -1515);
PAINT BLUE (1375 -1515);
DISPLAY INVISIBLE (1375 -1515);
FORCEPROP 2 LAST PART_TYPE SMLF
J 0
(1375 -1325);
DISPLAY 1.021277 (1375 -1325);
FORCEPROP 1 LAST MATERIAL IND
J 0
(1375 -1465);
DISPLAY 0.617021 (1375 -1465);
PAINT SKYBLUE (1375 -1465);
FORCEPROP 2 LAST VALUE 150NH
J 0
(1375 -1375);
DISPLAY 0.617021 (1375 -1375);
PAINT SKYBLUE (1375 -1375);
FORCEPROP 1 LAST LOCATION PL28
J 0
(1375 -1420);
DISPLAY 0.617021 (1375 -1420);
PAINT AQUA (1375 -1420);
FORCEPROP 2 LASTPIN (1200 -1550) $PN 1
J 2
(1190 -1540);
DISPLAY 0.617021 (1190 -1540);
PAINT MONO (1190 -1540);
FORCEPROP 2 LASTPIN (1200 -1800) $PN 2
J 2
(1190 -1790);
DISPLAY 0.617021 (1190 -1790);
PAINT MONO (1190 -1790);
FORCEPROP 2 LASTPIN (2000 -1800) $PN 3
J 0
(2010 -1790);
DISPLAY 0.617021 (2010 -1790);
PAINT MONO (2010 -1790);
FORCEPROP 2 LASTPIN (2000 -1550) $PN 4
J 0
(2010 -1540);
DISPLAY 0.617021 (2010 -1540);
PAINT MONO (2010 -1540);
FORCEPROP 1 LAST NEEDS_NO_SIZE TRUE
J 0
(1600 -1675);
DISPLAY 0.468085 (1600 -1675);
PAINT GREEN (1600 -1675);
DISPLAY INVISIBLE (1600 -1675);
FORCEPROP 2 LAST CDS_LIB pure_quanta
J 0
(1600 -1675);
DISPLAY INVISIBLE (1600 -1675);
FORCEPROP 2 LAST SEC_TYPE 
J 0
(1375 -1275);
DISPLAY 1.021277 (1375 -1275);
DISPLAY INVISIBLE (1375 -1275);
FORCEPROP 1 LAST PATH I37
J 0
(1800 -1520);
DISPLAY 0.723404 (1800 -1520);
PAINT GREEN (1800 -1520);
DISPLAY INVISIBLE (1800 -1520);
FORCEPROP 2 LAST SEC 1
J 0
(1375 -1275);
DISPLAY 0.680851 (1375 -1275);
PAINT MONO (1375 -1275);
DISPLAY INVISIBLE (1375 -1275);
FORCEADD Q_RES..1
(1525 -2175);
FORCEPROP 1 LAST PART_NUMBER CS00002JB13
J 0
(1400 -2125);
DISPLAY 0.617021 (1400 -2125);
PAINT BLUE (1400 -2125);
DISPLAY INVISIBLE (1400 -2125);
FORCEPROP 1 LAST PACK_TYPE 0402LF
J 0
(1400 -2075);
DISPLAY 0.617021 (1400 -2075);
PAINT SKYBLUE (1400 -2075);
FORCEPROP 1 LAST VALUE 0
J 2
(1700 -2175);
DISPLAY 0.617021 (1700 -2175);
PAINT SKYBLUE (1700 -2175);
FORCEPROP 1 LAST TOLERANCE 5%
J 0
(1725 -2175);
DISPLAY 0.617021 (1725 -2175);
PAINT SKYBLUE (1725 -2175);
FORCEPROP 1 LAST MATERIAL CHIP
J 0
(1800 -2175);
DISPLAY 0.617021 (1800 -2175);
PAINT SKYBLUE (1800 -2175);
FORCEPROP 1 LAST WATTAGE 1/16W
J 2
(1775 -2075);
DISPLAY 0.617021 (1775 -2075);
PAINT SKYBLUE (1775 -2075);
FORCEPROP 1 LAST LOCATION PR301
J 0
(1250 -2175);
DISPLAY 0.617021 (1250 -2175);
PAINT AQUA (1250 -2175);
FORCEPROP 1 LASTPIN (1425 -2175) $PN 1
J 0
(1437 -2163);
DISPLAY 0.617021 (1437 -2163);
PAINT MONO (1437 -2163);
FORCEPROP 1 LASTPIN (1625 -2175) $PN 2
J 0
(1587 -2163);
DISPLAY 0.617021 (1587 -2163);
PAINT MONO (1587 -2163);
FORCEPROP 2 LAST CDS_LIB pure_quanta
J 0
(1525 -2175);
DISPLAY INVISIBLE (1525 -2175);
FORCEPROP 1 LAST PATH I38
J 0
(1475 -2025);
DISPLAY 0.978723 (1475 -2025);
PAINT WHITE (1475 -2025);
DISPLAY INVISIBLE (1475 -2025);
FORCEPROP 0 LAST $SEC 1
J 0
(1775 -2025);
DISPLAY 0.680851 (1775 -2025);
PAINT MONO (1775 -2025);
DISPLAY INVISIBLE (1775 -2025);
FORCEPROP 0 LAST CDS_SEC 1
J 0
(1775 -2025);
DISPLAY 1.021277 (1775 -2025);
DISPLAY INVISIBLE (1775 -2025);
FORCEADD Q_CAP..1
R 2
(1125 -1275);
FORCEPROP 1 LAST PART_NUMBER CH4106K1B01
J 2
(1075 -1350);
DISPLAY 0.617021 (1075 -1350);
PAINT BLUE (1075 -1350);
DISPLAY INVISIBLE (1075 -1350);
FORCEPROP 1 LAST PACK_TYPE C0402
J 2
(1075 -1375);
DISPLAY 0.617021 (1075 -1375);
PAINT SKYBLUE (1075 -1375);
FORCEPROP 1 LAST VOLTAGE 50V
J 2
(1075 -1275);
DISPLAY 0.617021 (1075 -1275);
PAINT SKYBLUE (1075 -1275);
FORCEPROP 1 LAST VALUE 100NF
J 2
(1075 -1250);
DISPLAY 0.617021 (1075 -1250);
PAINT SKYBLUE (1075 -1250);
FORCEPROP 1 LAST TOLERANCE 10%
J 2
(1075 -1300);
DISPLAY 0.617021 (1075 -1300);
PAINT SKYBLUE (1075 -1300);
FORCEPROP 1 LAST MATERIAL X7R
J 2
(1075 -1325);
DISPLAY 0.617021 (1075 -1325);
PAINT SKYBLUE (1075 -1325);
FORCEPROP 1 LAST LOCATION PC531
J 2
(1075 -1200);
DISPLAY 0.617021 (1075 -1200);
PAINT AQUA (1075 -1200);
FORCEPROP 1 LASTPIN (1125 -1175) $PN 1
J 2
(1115 -1195);
DISPLAY 0.617021 (1115 -1195);
FORCEPROP 1 LASTPIN (1125 -1375) $PN 2
J 2
(1115 -1395);
DISPLAY 0.617021 (1115 -1395);
FORCEPROP 2 LAST CDS_LIB pure_quanta
J 2
(1125 -1275);
PAINT MONO (1125 -1275);
DISPLAY INVISIBLE (1125 -1275);
FORCEPROP 1 LAST PATH I39
J 2
(1075 -1125);
DISPLAY 0.978723 (1075 -1125);
PAINT WHITE (1075 -1125);
DISPLAY INVISIBLE (1075 -1125);
FORCEPROP 2 LAST $SEC 1
J 0
(1075 -1075);
DISPLAY 0.680851 (1075 -1075);
PAINT MONO (1075 -1075);
DISPLAY INVISIBLE (1075 -1075);
FORCEPROP 2 LAST CDS_SEC 1
J 0
(1075 -1075);
DISPLAY 1.021277 (1075 -1075);
DISPLAY INVISIBLE (1075 -1075);
FORCEADD OFFPAGE..1
(-2300 -2150);
FORCEPROP 2 LAST $XR0 284 
J 0
(-2726 -2150);
DISPLAY 0.638298 (-2726 -2150);
PAINT MONO (-2726 -2150);
FORCEPROP 1 LAST COMMENT_BODY TRUE
J 0
(-2175 -2250);
DISPLAY 0.872340 (-2175 -2250);
PAINT GREEN (-2175 -2250);
DISPLAY INVISIBLE (-2175 -2250);
FORCEPROP 1 LAST OFFPAGE TRUE
J 0
(-1975 -2275);
DISPLAY 0.872340 (-1975 -2275);
PAINT GREEN (-1975 -2275);
DISPLAY INVISIBLE (-1975 -2275);
FORCEPROP 2 LAST CDS_LIB standard
J 0
(-2300 -2150);
DISPLAY INVISIBLE (-2300 -2150);
FORCEPROP 2 LAST PATH I4
J 0
(-2725 -2100);
DISPLAY 1.021277 (-2725 -2100);
DISPLAY INVISIBLE (-2725 -2100);
FORCEADD OFFPAGE..3
(2800 -1800);
FORCEPROP 2 LAST $XR0 286 
J 0
(3104 -1800);
DISPLAY 0.638298 (3104 -1800);
PAINT MONO (3104 -1800);
FORCEPROP 2 LAST CDS_LIB standard
J 0
(2800 -1800);
DISPLAY INVISIBLE (2800 -1800);
FORCEPROP 1 LAST OFFPAGE TRUE
J 0
(3125 -1925);
DISPLAY 0.872340 (3125 -1925);
PAINT GREEN (3125 -1925);
DISPLAY INVISIBLE (3125 -1925);
FORCEPROP 1 LAST COMMENT_BODY TRUE
J 0
(2750 -1900);
DISPLAY 0.872340 (2750 -1900);
PAINT GREEN (2750 -1900);
DISPLAY INVISIBLE (2750 -1900);
FORCEPROP 2 LAST PATH I40
J 0
(3125 -1750);
DISPLAY 1.021277 (3125 -1750);
DISPLAY INVISIBLE (3125 -1750);
FORCEADD Q_CAP..1
(1150 -650);
FORCEPROP 1 LAST PART_NUMBER CH6223MEA01
J 0
(1200 -800);
DISPLAY 0.617021 (1200 -800);
PAINT BLUE (1200 -800);
DISPLAY INVISIBLE (1200 -800);
FORCEPROP 1 LAST PACK_TYPE C0805
J 0
(1200 -750);
DISPLAY 0.617021 (1200 -750);
PAINT SKYBLUE (1200 -750);
FORCEPROP 1 LAST VOLTAGE 16V
J 0
(1200 -600);
DISPLAY 0.617021 (1200 -600);
PAINT SKYBLUE (1200 -600);
FORCEPROP 1 LAST VALUE 22UF
J 0
(1200 -550);
DISPLAY 0.617021 (1200 -550);
PAINT SKYBLUE (1200 -550);
FORCEPROP 1 LAST TOLERANCE 20%
J 0
(1200 -650);
DISPLAY 0.617021 (1200 -650);
PAINT SKYBLUE (1200 -650);
FORCEPROP 1 LAST MATERIAL X6S
J 0
(1200 -700);
DISPLAY 0.617021 (1200 -700);
PAINT SKYBLUE (1200 -700);
FORCEPROP 1 LAST LOCATION PC535_P1_4
J 0
(1200 -500);
DISPLAY 0.617021 (1200 -500);
PAINT AQUA (1200 -500);
FORCEPROP 1 LASTPIN (1150 -550) $PN 1
J 0
(1160 -570);
DISPLAY 0.617021 (1160 -570);
PAINT MONO (1160 -570);
FORCEPROP 1 LASTPIN (1150 -750) $PN 2
J 0
(1160 -770);
DISPLAY 0.617021 (1160 -770);
PAINT MONO (1160 -770);
FORCEPROP 2 LAST CDS_LIB pure_quanta
J 0
(1150 -650);
DISPLAY INVISIBLE (1150 -650);
FORCEPROP 1 LAST PATH I41
J 0
(1200 -500);
DISPLAY 0.978723 (1200 -500);
PAINT WHITE (1200 -500);
DISPLAY INVISIBLE (1200 -500);
FORCEPROP 1 LAST LOCATION PC535_P1_4
J 0
(1200 -450);
DISPLAY 1.021277 (1200 -450);
PAINT AQUA (1200 -450);
DISPLAY INVISIBLE (1200 -450);
FORCEPROP 0 LAST $SEC 1
J 0
(1200 -450);
DISPLAY 0.680851 (1200 -450);
PAINT MONO (1200 -450);
DISPLAY INVISIBLE (1200 -450);
FORCEPROP 0 LAST CDS_SEC 1
J 0
(1200 -450);
DISPLAY 1.021277 (1200 -450);
DISPLAY INVISIBLE (1200 -450);
FORCEADD Q_CAP..1
(1525 -650);
FORCEPROP 1 LAST PART_NUMBER CH6223MEA01
J 0
(1575 -800);
DISPLAY 0.617021 (1575 -800);
PAINT BLUE (1575 -800);
DISPLAY INVISIBLE (1575 -800);
FORCEPROP 1 LAST PACK_TYPE C0805
J 0
(1575 -750);
DISPLAY 0.617021 (1575 -750);
PAINT SKYBLUE (1575 -750);
FORCEPROP 1 LAST VOLTAGE 16V
J 0
(1575 -600);
DISPLAY 0.617021 (1575 -600);
PAINT SKYBLUE (1575 -600);
FORCEPROP 1 LAST VALUE 22UF
J 0
(1575 -550);
DISPLAY 0.617021 (1575 -550);
PAINT SKYBLUE (1575 -550);
FORCEPROP 1 LAST TOLERANCE 20%
J 0
(1575 -650);
DISPLAY 0.617021 (1575 -650);
PAINT SKYBLUE (1575 -650);
FORCEPROP 1 LAST MATERIAL X6S
J 0
(1575 -700);
DISPLAY 0.617021 (1575 -700);
PAINT SKYBLUE (1575 -700);
FORCEPROP 1 LAST LOCATION PC537_P1_4
J 0
(1575 -500);
DISPLAY 0.617021 (1575 -500);
PAINT AQUA (1575 -500);
FORCEPROP 1 LASTPIN (1525 -550) $PN 1
J 0
(1535 -570);
DISPLAY 0.617021 (1535 -570);
PAINT MONO (1535 -570);
FORCEPROP 1 LASTPIN (1525 -750) $PN 2
J 0
(1535 -770);
DISPLAY 0.617021 (1535 -770);
PAINT MONO (1535 -770);
FORCEPROP 2 LAST CDS_LIB pure_quanta
J 0
(1525 -650);
DISPLAY INVISIBLE (1525 -650);
FORCEPROP 1 LAST PATH I42
J 0
(1575 -500);
DISPLAY 0.978723 (1575 -500);
PAINT WHITE (1575 -500);
DISPLAY INVISIBLE (1575 -500);
FORCEPROP 1 LAST LOCATION PC537_P1_4
J 0
(1575 -450);
DISPLAY 1.021277 (1575 -450);
PAINT AQUA (1575 -450);
DISPLAY INVISIBLE (1575 -450);
FORCEPROP 0 LAST $SEC 1
J 0
(1575 -450);
DISPLAY 0.680851 (1575 -450);
PAINT MONO (1575 -450);
DISPLAY INVISIBLE (1575 -450);
FORCEPROP 0 LAST CDS_SEC 1
J 0
(1575 -450);
DISPLAY 1.021277 (1575 -450);
DISPLAY INVISIBLE (1575 -450);
FORCEADD UNIVERSAL_GND..1
(1750 -1075);
FORCEPROP 3 LASTPIN (1750 -1025) SIG_NAME GND\g
J 0
(1760 -1015);
DISPLAY 0.659574 (1760 -1015);
PAINT MONO (1760 -1015);
DISPLAY INVISIBLE (1760 -1015);
FORCEPROP 1 LAST HDL_POWER GND
J 1
(1775 -1150);
DISPLAY 0.872340 (1775 -1150);
PAINT GREEN (1775 -1150);
DISPLAY INVISIBLE (1775 -1150);
FORCEPROP 2 LAST CDS_LIB logical_power
J 0
(1750 -1075);
PAINT MONO (1750 -1075);
DISPLAY INVISIBLE (1750 -1075);
FORCEPROP 1 LAST PATH I43
J 0
(1825 -1075);
DISPLAY 0.872340 (1825 -1075);
PAINT AQUA (1825 -1075);
DISPLAY INVISIBLE (1825 -1075);
FORCEADD VCC15..1
(1750 -275);
FORCEPROP 3 LASTPIN (1750 -325) SIG_NAME SW_P12V_PVCCIN_CPU1_FLT\g
J 0
(1760 -315);
DISPLAY 0.659574 (1760 -315);
PAINT MONO (1760 -315);
DISPLAY INVISIBLE (1760 -315);
FORCEPROP 1 LAST HDL_POWER SW_P12V_PVCCIN_CPU1_FLT
J 1
(1800 -225);
DISPLAY 0.617021 (1800 -225);
PAINT GREEN (1800 -225);
FORCEPROP 2 LAST CDS_LIB logical_power
J 0
(1750 -275);
DISPLAY INVISIBLE (1750 -275);
FORCEPROP 1 LAST PATH I44
J 0
(1800 -250);
DISPLAY 0.872340 (1800 -250);
PAINT AQUA (1800 -250);
DISPLAY INVISIBLE (1800 -250);
FORCEADD Q_RES..1
(1575 650);
FORCEPROP 1 LAST PART_NUMBER CS00002JB13
J 0
(1450 700);
DISPLAY 0.617021 (1450 700);
PAINT BLUE (1450 700);
DISPLAY INVISIBLE (1450 700);
FORCEPROP 1 LAST PACK_TYPE 0402LF
J 0
(1450 750);
DISPLAY 0.617021 (1450 750);
PAINT SKYBLUE (1450 750);
FORCEPROP 1 LAST MATERIAL CHIP
J 0
(1850 650);
DISPLAY 0.617021 (1850 650);
PAINT SKYBLUE (1850 650);
FORCEPROP 1 LAST VALUE 0
J 2
(1750 650);
DISPLAY 0.617021 (1750 650);
PAINT SKYBLUE (1750 650);
FORCEPROP 1 LAST TOLERANCE 5%
J 0
(1775 650);
DISPLAY 0.617021 (1775 650);
PAINT SKYBLUE (1775 650);
FORCEPROP 1 LAST WATTAGE 1/16W
J 2
(1825 750);
DISPLAY 0.617021 (1825 750);
PAINT SKYBLUE (1825 750);
FORCEPROP 1 LAST LOCATION PR302
J 0
(1300 650);
DISPLAY 0.617021 (1300 650);
PAINT AQUA (1300 650);
FORCEPROP 1 LASTPIN (1475 650) $PN 1
J 0
(1487 662);
DISPLAY 0.617021 (1487 662);
PAINT MONO (1487 662);
FORCEPROP 1 LASTPIN (1675 650) $PN 2
J 0
(1637 662);
DISPLAY 0.617021 (1637 662);
PAINT MONO (1637 662);
FORCEPROP 2 LAST CDS_LIB pure_quanta
J 0
(1575 650);
DISPLAY INVISIBLE (1575 650);
FORCEPROP 1 LAST PATH I45
J 0
(1525 800);
DISPLAY 0.978723 (1525 800);
PAINT WHITE (1525 800);
DISPLAY INVISIBLE (1525 800);
FORCEPROP 0 LAST $SEC 1
J 0
(1825 800);
DISPLAY 0.680851 (1825 800);
PAINT MONO (1825 800);
DISPLAY INVISIBLE (1825 800);
FORCEPROP 0 LAST CDS_SEC 1
J 0
(1825 800);
DISPLAY 1.021277 (1825 800);
DISPLAY INVISIBLE (1825 800);
FORCEADD Q_RES..1
(425 1725);
FORCEPROP 1 LAST PART_NUMBER CS-3302FB01
J 0
(325 1775);
DISPLAY 0.617021 (325 1775);
PAINT BLUE (325 1775);
DISPLAY INVISIBLE (325 1775);
FORCEPROP 1 LAST WATTAGE 1/16W
J 2
(550 1800);
DISPLAY 0.617021 (550 1800);
PAINT SKYBLUE (550 1800);
FORCEPROP 1 LAST PACK_TYPE 0402LF
J 0
(325 1800);
DISPLAY 0.617021 (325 1800);
PAINT SKYBLUE (325 1800);
FORCEPROP 1 LAST VALUE 3.3
J 2
(550 1725);
DISPLAY 0.617021 (550 1725);
PAINT SKYBLUE (550 1725);
FORCEPROP 1 LAST TOLERANCE 1%
J 0
(575 1725);
DISPLAY 0.617021 (575 1725);
PAINT SKYBLUE (575 1725);
FORCEPROP 1 LAST MATERIAL CHIP
J 0
(325 1825);
DISPLAY 0.617021 (325 1825);
PAINT SKYBLUE (325 1825);
FORCEPROP 1 LAST LOCATION PR1789
J 0
(225 1725);
DISPLAY 0.617021 (225 1725);
PAINT AQUA (225 1725);
FORCEPROP 1 LASTPIN (325 1725) $PN 1
J 0
(337 1737);
DISPLAY 0.617021 (337 1737);
FORCEPROP 1 LASTPIN (525 1725) $PN 2
J 0
(487 1737);
DISPLAY 0.617021 (487 1737);
FORCEPROP 2 LAST CDS_LIB pure_quanta
J 0
(425 1725);
PAINT MONO (425 1725);
DISPLAY INVISIBLE (425 1725);
FORCEPROP 1 LAST PATH I46
J 0
(375 1875);
DISPLAY 0.978723 (375 1875);
PAINT WHITE (375 1875);
DISPLAY INVISIBLE (375 1875);
FORCEPROP 2 LAST $SEC 1
J 0
(375 1925);
DISPLAY 0.680851 (375 1925);
PAINT MONO (375 1925);
DISPLAY INVISIBLE (375 1925);
FORCEPROP 2 LAST CDS_SEC 1
J 0
(375 1925);
DISPLAY 1.021277 (375 1925);
DISPLAY INVISIBLE (375 1925);
FORCEADD OFFPAGE..6
(650 1025);
FORCEPROP 2 LAST $XR0 286 
J 0
(370 1025);
DISPLAY 0.638298 (370 1025);
PAINT MONO (370 1025);
FORCEPROP 2 LAST CDS_LIB standard
J 0
(650 1025);
DISPLAY INVISIBLE (650 1025);
FORCEPROP 1 LAST OFFPAGE TRUE
J 0
(975 900);
DISPLAY 0.872340 (975 900);
PAINT GREEN (975 900);
DISPLAY INVISIBLE (975 900);
FORCEPROP 1 LAST COMMENT_BODY TRUE
J 0
(750 950);
DISPLAY 0.872340 (750 950);
PAINT GREEN (750 950);
DISPLAY INVISIBLE (750 950);
FORCEPROP 2 LAST PATH I47
J 0
(375 1075);
DISPLAY 1.021277 (375 1075);
DISPLAY INVISIBLE (375 1075);
FORCEADD Q_CAP..1
(-25 2175);
FORCEPROP 1 LAST PART_NUMBER TMP_QCH2336K1B12
J 0
(25 2025);
DISPLAY 0.617021 (25 2025);
PAINT BLUE (25 2025);
DISPLAY INVISIBLE (25 2025);
FORCEPROP 1 LAST PACK_TYPE 0402
J 0
(25 2075);
DISPLAY 0.617021 (25 2075);
PAINT SKYBLUE (25 2075);
FORCEPROP 1 LAST VOLTAGE 50V
J 0
(25 2225);
DISPLAY 0.617021 (25 2225);
PAINT SKYBLUE (25 2225);
FORCEPROP 1 LAST VALUE 3300PF
J 0
(25 2275);
DISPLAY 0.617021 (25 2275);
PAINT SKYBLUE (25 2275);
FORCEPROP 1 LAST TOLERANCE 10%
J 0
(25 2175);
DISPLAY 0.617021 (25 2175);
PAINT SKYBLUE (25 2175);
FORCEPROP 1 LAST MATERIAL X7R
J 0
(25 2125);
DISPLAY 0.617021 (25 2125);
PAINT SKYBLUE (25 2125);
FORCEPROP 1 LAST LOCATION PC528_P1_3
J 0
(25 2325);
DISPLAY 0.617021 (25 2325);
PAINT AQUA (25 2325);
FORCEPROP 1 LASTPIN (-25 2275) $PN 1
J 0
(-15 2255);
DISPLAY 0.617021 (-15 2255);
PAINT MONO (-15 2255);
FORCEPROP 1 LASTPIN (-25 2075) $PN 2
J 0
(-15 2055);
DISPLAY 0.617021 (-15 2055);
PAINT MONO (-15 2055);
FORCEPROP 2 LAST CDS_LIB pure_quanta
J 0
(-25 2175);
DISPLAY INVISIBLE (-25 2175);
FORCEPROP 1 LAST PATH I48
J 0
(25 2325);
DISPLAY 0.978723 (25 2325);
PAINT WHITE (25 2325);
DISPLAY INVISIBLE (25 2325);
FORCEPROP 1 LAST LOCATION PC528_P1_3
J 0
(25 2375);
DISPLAY 1.021277 (25 2375);
PAINT AQUA (25 2375);
DISPLAY INVISIBLE (25 2375);
FORCEPROP 0 LAST $SEC 1
J 0
(25 2375);
DISPLAY 0.680851 (25 2375);
PAINT MONO (25 2375);
DISPLAY INVISIBLE (25 2375);
FORCEPROP 0 LAST CDS_SEC 1
J 0
(25 2375);
DISPLAY 1.021277 (25 2375);
DISPLAY INVISIBLE (25 2375);
FORCEADD Q_CAP..1
(375 2175);
FORCEPROP 1 LAST PART_NUMBER CH5103KEB01
J 0
(425 2025);
DISPLAY 0.617021 (425 2025);
PAINT BLUE (425 2025);
DISPLAY INVISIBLE (425 2025);
FORCEPROP 1 LAST VOLTAGE 16V
J 0
(425 2225);
DISPLAY 0.617021 (425 2225);
PAINT SKYBLUE (425 2225);
FORCEPROP 1 LAST TOLERANCE 10%
J 0
(425 2175);
DISPLAY 0.617021 (425 2175);
PAINT SKYBLUE (425 2175);
FORCEPROP 1 LAST PACK_TYPE C0402
J 0
(425 2075);
DISPLAY 0.617021 (425 2075);
PAINT SKYBLUE (425 2075);
FORCEPROP 1 LAST VALUE 1UF
J 0
(425 2275);
DISPLAY 0.617021 (425 2275);
PAINT SKYBLUE (425 2275);
FORCEPROP 1 LAST MATERIAL X6S
J 0
(425 2125);
DISPLAY 0.617021 (425 2125);
PAINT SKYBLUE (425 2125);
FORCEPROP 1 LAST LOCATION PC530_P1_3
J 0
(425 2325);
DISPLAY 0.617021 (425 2325);
PAINT AQUA (425 2325);
FORCEPROP 1 LASTPIN (375 2275) $PN 1
J 0
(385 2255);
DISPLAY 0.617021 (385 2255);
PAINT MONO (385 2255);
FORCEPROP 1 LASTPIN (375 2075) $PN 2
J 0
(385 2055);
DISPLAY 0.617021 (385 2055);
PAINT MONO (385 2055);
FORCEPROP 2 LAST CDS_LIB pure_quanta
J 0
(375 2175);
DISPLAY INVISIBLE (375 2175);
FORCEPROP 1 LAST PATH I49
J 0
(425 2325);
DISPLAY 0.978723 (425 2325);
PAINT WHITE (425 2325);
DISPLAY INVISIBLE (425 2325);
FORCEPROP 1 LAST LOCATION PC530_P1_3
J 0
(425 2375);
DISPLAY 1.021277 (425 2375);
PAINT AQUA (425 2375);
DISPLAY INVISIBLE (425 2375);
FORCEPROP 0 LAST $SEC 1
J 0
(425 2375);
DISPLAY 0.680851 (425 2375);
PAINT MONO (425 2375);
DISPLAY INVISIBLE (425 2375);
FORCEPROP 0 LAST CDS_SEC 1
J 0
(425 2375);
DISPLAY 1.021277 (425 2375);
DISPLAY INVISIBLE (425 2375);
FORCEADD OFFPAGE..5
(-2300 -2050);
FORCEPROP 2 LAST $XR4 284 
J 0
(-2555 -1978);
DISPLAY 0.638298 (-2555 -1978);
PAINT MONO (-2555 -1978);
FORCEPROP 2 LAST $XR3 288 
J 0
(-2555 -2122);
DISPLAY 0.638298 (-2555 -2122);
PAINT MONO (-2555 -2122);
FORCEPROP 2 LAST $XR2 287 
J 0
(-2555 -2014);
DISPLAY 0.638298 (-2555 -2014);
PAINT MONO (-2555 -2014);
FORCEPROP 2 LAST $XR1 286 
J 0
(-2555 -2086);
DISPLAY 0.638298 (-2555 -2086);
PAINT MONO (-2555 -2086);
FORCEPROP 2 LAST $XR0 285 
J 0
(-2555 -2050);
DISPLAY 0.638298 (-2555 -2050);
PAINT MONO (-2555 -2050);
FORCEPROP 1 LAST COMMENT_BODY TRUE
J 0
(-2200 -2125);
DISPLAY 0.872340 (-2200 -2125);
PAINT GREEN (-2200 -2125);
DISPLAY INVISIBLE (-2200 -2125);
FORCEPROP 1 LAST OFFPAGE TRUE
J 0
(-1975 -2175);
DISPLAY 0.872340 (-1975 -2175);
PAINT GREEN (-1975 -2175);
DISPLAY INVISIBLE (-1975 -2175);
FORCEPROP 2 LAST CDS_LIB standard
J 0
(-2300 -2050);
DISPLAY INVISIBLE (-2300 -2050);
FORCEPROP 2 LAST PATH I5
J 0
(-2550 -1925);
DISPLAY 1.021277 (-2550 -1925);
DISPLAY INVISIBLE (-2550 -1925);
FORCEADD Q_CAP..1
(775 2175);
FORCEPROP 1 LAST PART_NUMBER CH6223MEA01
J 0
(825 2025);
DISPLAY 0.617021 (825 2025);
PAINT BLUE (825 2025);
DISPLAY INVISIBLE (825 2025);
FORCEPROP 1 LAST MATERIAL X6S
J 0
(825 2125);
DISPLAY 0.617021 (825 2125);
PAINT SKYBLUE (825 2125);
FORCEPROP 1 LAST VOLTAGE 16V
J 0
(825 2225);
DISPLAY 0.617021 (825 2225);
PAINT SKYBLUE (825 2225);
FORCEPROP 1 LAST PACK_TYPE C0805
J 0
(825 2075);
DISPLAY 0.617021 (825 2075);
PAINT SKYBLUE (825 2075);
FORCEPROP 1 LAST VALUE 22UF
J 0
(825 2275);
DISPLAY 0.617021 (825 2275);
PAINT SKYBLUE (825 2275);
FORCEPROP 1 LAST TOLERANCE 20%
J 0
(825 2175);
DISPLAY 0.617021 (825 2175);
PAINT SKYBLUE (825 2175);
FORCEPROP 1 LAST LOCATION PC534_P1_3
J 0
(825 2325);
DISPLAY 0.617021 (825 2325);
PAINT AQUA (825 2325);
FORCEPROP 1 LASTPIN (775 2275) $PN 1
J 0
(785 2255);
DISPLAY 0.617021 (785 2255);
PAINT MONO (785 2255);
FORCEPROP 1 LASTPIN (775 2075) $PN 2
J 0
(785 2055);
DISPLAY 0.617021 (785 2055);
PAINT MONO (785 2055);
FORCEPROP 2 LAST CDS_LIB pure_quanta
J 0
(775 2175);
DISPLAY INVISIBLE (775 2175);
FORCEPROP 1 LAST PATH I50
J 0
(825 2325);
DISPLAY 0.978723 (825 2325);
PAINT WHITE (825 2325);
DISPLAY INVISIBLE (825 2325);
FORCEPROP 1 LAST LOCATION PC534_P1_3
J 0
(825 2375);
DISPLAY 1.021277 (825 2375);
PAINT AQUA (825 2375);
DISPLAY INVISIBLE (825 2375);
FORCEPROP 0 LAST $SEC 1
J 0
(825 2375);
DISPLAY 0.680851 (825 2375);
PAINT MONO (825 2375);
DISPLAY INVISIBLE (825 2375);
FORCEPROP 0 LAST CDS_SEC 1
J 0
(825 2375);
DISPLAY 1.021277 (825 2375);
DISPLAY INVISIBLE (825 2375);
FORCEADD Q_INDUCTOR4P_14..1
(1625 1150);
FORCEPROP 1 LAST PART_NUMBER CV+15^0TZ04
J 0
(1400 1310);
DISPLAY 0.617021 (1400 1310);
PAINT BLUE (1400 1310);
DISPLAY INVISIBLE (1400 1310);
FORCEPROP 1 LAST MATERIAL IND
J 0
(1400 1360);
DISPLAY 0.617021 (1400 1360);
PAINT SKYBLUE (1400 1360);
FORCEPROP 2 LAST VALUE 150NH
J 0
(1400 1450);
DISPLAY 0.617021 (1400 1450);
PAINT SKYBLUE (1400 1450);
FORCEPROP 2 LAST PART_TYPE SMLF
J 0
(1400 1500);
DISPLAY 1.021277 (1400 1500);
FORCEPROP 1 LAST LOCATION PL29
J 0
(1400 1405);
DISPLAY 0.617021 (1400 1405);
PAINT AQUA (1400 1405);
FORCEPROP 2 LASTPIN (1225 1275) $PN 1
J 2
(1215 1285);
DISPLAY 0.617021 (1215 1285);
PAINT MONO (1215 1285);
FORCEPROP 2 LASTPIN (1225 1025) $PN 2
J 2
(1215 1035);
DISPLAY 0.617021 (1215 1035);
PAINT MONO (1215 1035);
FORCEPROP 2 LASTPIN (2025 1025) $PN 3
J 0
(2035 1035);
DISPLAY 0.617021 (2035 1035);
PAINT MONO (2035 1035);
FORCEPROP 2 LASTPIN (2025 1275) $PN 4
J 0
(2035 1285);
DISPLAY 0.617021 (2035 1285);
PAINT MONO (2035 1285);
FORCEPROP 2 LAST SEC_TYPE 
J 0
(1400 1550);
DISPLAY 1.021277 (1400 1550);
DISPLAY INVISIBLE (1400 1550);
FORCEPROP 2 LAST CDS_LIB pure_quanta
J 0
(1625 1150);
DISPLAY INVISIBLE (1625 1150);
FORCEPROP 1 LAST NEEDS_NO_SIZE TRUE
J 0
(1625 1150);
DISPLAY 0.468085 (1625 1150);
PAINT GREEN (1625 1150);
DISPLAY INVISIBLE (1625 1150);
FORCEPROP 1 LAST PATH I51
J 0
(1825 1305);
DISPLAY 0.723404 (1825 1305);
PAINT GREEN (1825 1305);
DISPLAY INVISIBLE (1825 1305);
FORCEPROP 2 LAST SEC 1
J 0
(1400 1550);
DISPLAY 0.680851 (1400 1550);
PAINT MONO (1400 1550);
DISPLAY INVISIBLE (1400 1550);
FORCEADD Q_CAP..1
R 2
(1150 1550);
FORCEPROP 1 LAST PART_NUMBER CH4106K1B01
J 2
(1100 1475);
DISPLAY 0.617021 (1100 1475);
PAINT BLUE (1100 1475);
DISPLAY INVISIBLE (1100 1475);
FORCEPROP 1 LAST PACK_TYPE C0402
J 2
(1100 1450);
DISPLAY 0.617021 (1100 1450);
PAINT SKYBLUE (1100 1450);
FORCEPROP 1 LAST VOLTAGE 50V
J 2
(1100 1550);
DISPLAY 0.617021 (1100 1550);
PAINT SKYBLUE (1100 1550);
FORCEPROP 1 LAST VALUE 100NF
J 2
(1100 1575);
DISPLAY 0.617021 (1100 1575);
PAINT SKYBLUE (1100 1575);
FORCEPROP 1 LAST TOLERANCE 10%
J 2
(1100 1525);
DISPLAY 0.617021 (1100 1525);
PAINT SKYBLUE (1100 1525);
FORCEPROP 1 LAST MATERIAL X7R
J 2
(1100 1500);
DISPLAY 0.617021 (1100 1500);
PAINT SKYBLUE (1100 1500);
FORCEPROP 1 LAST LOCATION PC532
J 2
(1100 1625);
DISPLAY 0.617021 (1100 1625);
PAINT AQUA (1100 1625);
FORCEPROP 1 LASTPIN (1150 1650) $PN 1
J 2
(1140 1630);
DISPLAY 0.617021 (1140 1630);
FORCEPROP 1 LASTPIN (1150 1450) $PN 2
J 2
(1140 1430);
DISPLAY 0.617021 (1140 1430);
FORCEPROP 2 LAST CDS_LIB pure_quanta
J 2
(1150 1550);
PAINT MONO (1150 1550);
DISPLAY INVISIBLE (1150 1550);
FORCEPROP 1 LAST PATH I52
J 2
(1100 1700);
DISPLAY 0.978723 (1100 1700);
PAINT WHITE (1100 1700);
DISPLAY INVISIBLE (1100 1700);
FORCEPROP 2 LAST $SEC 1
J 0
(1100 1750);
DISPLAY 0.680851 (1100 1750);
PAINT MONO (1100 1750);
DISPLAY INVISIBLE (1100 1750);
FORCEPROP 2 LAST CDS_SEC 1
J 0
(1100 1750);
DISPLAY 1.021277 (1100 1750);
DISPLAY INVISIBLE (1100 1750);
FORCEADD UNIVERSAL_GND..1
(1775 1750);
FORCEPROP 3 LASTPIN (1775 1800) SIG_NAME GND\g
J 0
(1785 1810);
DISPLAY 0.659574 (1785 1810);
PAINT MONO (1785 1810);
DISPLAY INVISIBLE (1785 1810);
FORCEPROP 1 LAST HDL_POWER GND
J 1
(1800 1675);
DISPLAY 0.872340 (1800 1675);
PAINT GREEN (1800 1675);
DISPLAY INVISIBLE (1800 1675);
FORCEPROP 2 LAST CDS_LIB logical_power
J 0
(1775 1750);
PAINT MONO (1775 1750);
DISPLAY INVISIBLE (1775 1750);
FORCEPROP 1 LAST PATH I53
J 0
(1850 1750);
DISPLAY 0.872340 (1850 1750);
PAINT AQUA (1850 1750);
DISPLAY INVISIBLE (1850 1750);
FORCEADD Q_CAP..1
(1175 2175);
FORCEPROP 1 LAST PART_NUMBER CH6223MEA01
J 0
(1225 2025);
DISPLAY 0.617021 (1225 2025);
PAINT BLUE (1225 2025);
DISPLAY INVISIBLE (1225 2025);
FORCEPROP 1 LAST PACK_TYPE C0805
J 0
(1225 2075);
DISPLAY 0.617021 (1225 2075);
PAINT SKYBLUE (1225 2075);
FORCEPROP 1 LAST VOLTAGE 16V
J 0
(1225 2225);
DISPLAY 0.617021 (1225 2225);
PAINT SKYBLUE (1225 2225);
FORCEPROP 1 LAST VALUE 22UF
J 0
(1225 2275);
DISPLAY 0.617021 (1225 2275);
PAINT SKYBLUE (1225 2275);
FORCEPROP 1 LAST TOLERANCE 20%
J 0
(1225 2175);
DISPLAY 0.617021 (1225 2175);
PAINT SKYBLUE (1225 2175);
FORCEPROP 1 LAST MATERIAL X6S
J 0
(1225 2125);
DISPLAY 0.617021 (1225 2125);
PAINT SKYBLUE (1225 2125);
FORCEPROP 1 LAST LOCATION PC536_P1_3
J 0
(1225 2325);
DISPLAY 0.617021 (1225 2325);
PAINT AQUA (1225 2325);
FORCEPROP 1 LASTPIN (1175 2275) $PN 1
J 0
(1185 2255);
DISPLAY 0.617021 (1185 2255);
PAINT MONO (1185 2255);
FORCEPROP 1 LASTPIN (1175 2075) $PN 2
J 0
(1185 2055);
DISPLAY 0.617021 (1185 2055);
PAINT MONO (1185 2055);
FORCEPROP 2 LAST CDS_LIB pure_quanta
J 0
(1175 2175);
DISPLAY INVISIBLE (1175 2175);
FORCEPROP 1 LAST PATH I54
J 0
(1225 2325);
DISPLAY 0.978723 (1225 2325);
PAINT WHITE (1225 2325);
DISPLAY INVISIBLE (1225 2325);
FORCEPROP 1 LAST LOCATION PC536_P1_3
J 0
(1225 2375);
DISPLAY 1.021277 (1225 2375);
PAINT AQUA (1225 2375);
DISPLAY INVISIBLE (1225 2375);
FORCEPROP 0 LAST $SEC 1
J 0
(1225 2375);
DISPLAY 0.680851 (1225 2375);
PAINT MONO (1225 2375);
DISPLAY INVISIBLE (1225 2375);
FORCEPROP 0 LAST CDS_SEC 1
J 0
(1225 2375);
DISPLAY 1.021277 (1225 2375);
DISPLAY INVISIBLE (1225 2375);
FORCEADD Q_CAP..1
(1550 2175);
FORCEPROP 1 LAST PART_NUMBER CH6223MEA01
J 0
(1600 2025);
DISPLAY 0.617021 (1600 2025);
PAINT BLUE (1600 2025);
DISPLAY INVISIBLE (1600 2025);
FORCEPROP 1 LAST PACK_TYPE C0805
J 0
(1600 2075);
DISPLAY 0.617021 (1600 2075);
PAINT SKYBLUE (1600 2075);
FORCEPROP 1 LAST VOLTAGE 16V
J 0
(1600 2225);
DISPLAY 0.617021 (1600 2225);
PAINT SKYBLUE (1600 2225);
FORCEPROP 1 LAST VALUE 22UF
J 0
(1600 2275);
DISPLAY 0.617021 (1600 2275);
PAINT SKYBLUE (1600 2275);
FORCEPROP 1 LAST TOLERANCE 20%
J 0
(1600 2175);
DISPLAY 0.617021 (1600 2175);
PAINT SKYBLUE (1600 2175);
FORCEPROP 1 LAST MATERIAL X6S
J 0
(1600 2125);
DISPLAY 0.617021 (1600 2125);
PAINT SKYBLUE (1600 2125);
FORCEPROP 1 LAST LOCATION PC538_P1_3
J 0
(1600 2325);
DISPLAY 0.617021 (1600 2325);
PAINT AQUA (1600 2325);
FORCEPROP 1 LASTPIN (1550 2275) $PN 1
J 0
(1560 2255);
DISPLAY 0.617021 (1560 2255);
PAINT MONO (1560 2255);
FORCEPROP 1 LASTPIN (1550 2075) $PN 2
J 0
(1560 2055);
DISPLAY 0.617021 (1560 2055);
PAINT MONO (1560 2055);
FORCEPROP 2 LAST CDS_LIB pure_quanta
J 0
(1550 2175);
DISPLAY INVISIBLE (1550 2175);
FORCEPROP 1 LAST PATH I55
J 0
(1600 2325);
DISPLAY 0.978723 (1600 2325);
PAINT WHITE (1600 2325);
DISPLAY INVISIBLE (1600 2325);
FORCEPROP 1 LAST LOCATION PC538_P1_3
J 0
(1600 2375);
DISPLAY 1.021277 (1600 2375);
PAINT AQUA (1600 2375);
DISPLAY INVISIBLE (1600 2375);
FORCEPROP 0 LAST $SEC 1
J 0
(1600 2375);
DISPLAY 0.680851 (1600 2375);
PAINT MONO (1600 2375);
DISPLAY INVISIBLE (1600 2375);
FORCEPROP 0 LAST CDS_SEC 1
J 0
(1600 2375);
DISPLAY 1.021277 (1600 2375);
DISPLAY INVISIBLE (1600 2375);
FORCEADD VCC15..1
(1775 2550);
FORCEPROP 3 LASTPIN (1775 2500) SIG_NAME SW_P12V_PVCCIN_CPU1_FLT\g
J 0
(1785 2510);
DISPLAY 0.659574 (1785 2510);
PAINT MONO (1785 2510);
DISPLAY INVISIBLE (1785 2510);
FORCEPROP 1 LAST HDL_POWER SW_P12V_PVCCIN_CPU1_FLT
J 1
(1825 2600);
DISPLAY 0.617021 (1825 2600);
PAINT GREEN (1825 2600);
FORCEPROP 2 LAST CDS_LIB logical_power
J 0
(1775 2550);
DISPLAY INVISIBLE (1775 2550);
FORCEPROP 1 LAST PATH I56
J 0
(1825 2575);
DISPLAY 0.872340 (1825 2575);
PAINT AQUA (1825 2575);
DISPLAY INVISIBLE (1825 2575);
FORCEADD OFFPAGE..3
(2575 1025);
FORCEPROP 2 LAST $XR0 285 
J 0
(2789 1025);
DISPLAY 0.638298 (2789 1025);
PAINT MONO (2789 1025);
FORCEPROP 1 LAST COMMENT_BODY TRUE
J 0
(2525 925);
DISPLAY 0.872340 (2525 925);
PAINT GREEN (2525 925);
DISPLAY INVISIBLE (2525 925);
FORCEPROP 1 LAST OFFPAGE TRUE
J 0
(2900 900);
DISPLAY 0.872340 (2900 900);
PAINT GREEN (2900 900);
DISPLAY INVISIBLE (2900 900);
FORCEPROP 2 LAST CDS_LIB standard
J 0
(2575 1025);
DISPLAY INVISIBLE (2575 1025);
FORCEPROP 2 LAST PATH I57
J 0
(2800 1075);
DISPLAY 1.021277 (2800 1075);
DISPLAY INVISIBLE (2800 1075);
FORCEADD Q_CAP..1
(3325 -1750);
FORCEPROP 1 LAST PART_NUMBER CH622KMEA03
J 0
(3375 -1925);
DISPLAY 0.617021 (3375 -1925);
PAINT BLUE (3375 -1925);
DISPLAY INVISIBLE (3375 -1925);
FORCEPROP 1 LAST PACK_TYPE C0805
J 0
(3375 -1875);
DISPLAY 0.617021 (3375 -1875);
PAINT SKYBLUE (3375 -1875);
FORCEPROP 1 LAST MATERIAL X6S
J 0
(3375 -1825);
DISPLAY 0.617021 (3375 -1825);
PAINT SKYBLUE (3375 -1825);
FORCEPROP 1 LAST TOLERANCE 20%
J 0
(3375 -1775);
DISPLAY 0.617021 (3375 -1775);
PAINT SKYBLUE (3375 -1775);
FORCEPROP 1 LAST VALUE 22UF
J 0
(3375 -1675);
DISPLAY 0.617021 (3375 -1675);
PAINT SKYBLUE (3375 -1675);
FORCEPROP 1 LAST VOLTAGE 4V
J 0
(3375 -1725);
DISPLAY 0.617021 (3375 -1725);
PAINT SKYBLUE (3375 -1725);
FORCEPROP 1 LAST LOCATION PC541_P1_4
J 0
(3375 -1625);
DISPLAY 0.617021 (3375 -1625);
PAINT AQUA (3375 -1625);
FORCEPROP 1 LASTPIN (3325 -1650) $PN 1
J 0
(3335 -1670);
DISPLAY 0.617021 (3335 -1670);
PAINT MONO (3335 -1670);
FORCEPROP 1 LASTPIN (3325 -1850) $PN 2
J 0
(3335 -1870);
DISPLAY 0.617021 (3335 -1870);
PAINT MONO (3335 -1870);
FORCEPROP 2 LAST CDS_LIB pure_quanta
J 0
(3325 -1750);
DISPLAY INVISIBLE (3325 -1750);
FORCEPROP 1 LAST PATH I58
J 0
(3375 -1600);
DISPLAY 0.978723 (3375 -1600);
PAINT WHITE (3375 -1600);
DISPLAY INVISIBLE (3375 -1600);
FORCEPROP 1 LAST LOCATION PC541_P1_4
J 0
(3375 -1575);
DISPLAY 1.021277 (3375 -1575);
PAINT AQUA (3375 -1575);
DISPLAY INVISIBLE (3375 -1575);
FORCEPROP 0 LAST $SEC 1
J 0
(3375 -1575);
DISPLAY 0.680851 (3375 -1575);
PAINT MONO (3375 -1575);
DISPLAY INVISIBLE (3375 -1575);
FORCEPROP 0 LAST CDS_SEC 1
J 0
(3375 -1575);
DISPLAY 1.021277 (3375 -1575);
DISPLAY INVISIBLE (3375 -1575);
FORCEADD Q_CAP..1
(3750 -1750);
FORCEPROP 1 LAST PART_NUMBER CH622KMEA03
J 0
(3800 -1925);
DISPLAY 0.617021 (3800 -1925);
PAINT BLUE (3800 -1925);
DISPLAY INVISIBLE (3800 -1925);
FORCEPROP 1 LAST PACK_TYPE C0805
J 0
(3800 -1875);
DISPLAY 0.617021 (3800 -1875);
PAINT SKYBLUE (3800 -1875);
FORCEPROP 1 LAST MATERIAL X6S
J 0
(3800 -1825);
DISPLAY 0.617021 (3800 -1825);
PAINT SKYBLUE (3800 -1825);
FORCEPROP 1 LAST TOLERANCE 20%
J 0
(3800 -1775);
DISPLAY 0.617021 (3800 -1775);
PAINT SKYBLUE (3800 -1775);
FORCEPROP 1 LAST VALUE 22UF
J 0
(3800 -1675);
DISPLAY 0.617021 (3800 -1675);
PAINT SKYBLUE (3800 -1675);
FORCEPROP 1 LAST VOLTAGE 4V
J 0
(3800 -1725);
DISPLAY 0.617021 (3800 -1725);
PAINT SKYBLUE (3800 -1725);
FORCEPROP 1 LAST LOCATION PC543_P1_4
J 0
(3800 -1625);
DISPLAY 0.617021 (3800 -1625);
PAINT AQUA (3800 -1625);
FORCEPROP 1 LASTPIN (3750 -1650) $PN 1
J 0
(3760 -1670);
DISPLAY 0.617021 (3760 -1670);
PAINT MONO (3760 -1670);
FORCEPROP 1 LASTPIN (3750 -1850) $PN 2
J 0
(3760 -1870);
DISPLAY 0.617021 (3760 -1870);
PAINT MONO (3760 -1870);
FORCEPROP 2 LAST CDS_LIB pure_quanta
J 0
(3750 -1750);
DISPLAY INVISIBLE (3750 -1750);
FORCEPROP 1 LAST PATH I59
J 0
(3800 -1600);
DISPLAY 0.978723 (3800 -1600);
PAINT WHITE (3800 -1600);
DISPLAY INVISIBLE (3800 -1600);
FORCEPROP 1 LAST LOCATION PC543_P1_4
J 0
(3800 -1575);
DISPLAY 1.021277 (3800 -1575);
PAINT AQUA (3800 -1575);
DISPLAY INVISIBLE (3800 -1575);
FORCEPROP 0 LAST $SEC 1
J 0
(3800 -1575);
DISPLAY 0.680851 (3800 -1575);
PAINT MONO (3800 -1575);
DISPLAY INVISIBLE (3800 -1575);
FORCEPROP 0 LAST CDS_SEC 1
J 0
(3800 -1575);
DISPLAY 1.021277 (3800 -1575);
DISPLAY INVISIBLE (3800 -1575);
FORCEADD Q_CAP..2
(-2050 -1750);
FORCEPROP 1 LAST PART_NUMBER CH4104K1B00
J 1
(-1825 -1725);
DISPLAY 0.617021 (-1825 -1725);
PAINT BLUE (-1825 -1725);
DISPLAY INVISIBLE (-1825 -1725);
FORCEPROP 1 LAST PACK_TYPE 0402
J 1
(-1675 -1750);
DISPLAY 0.617021 (-1675 -1750);
PAINT SKYBLUE (-1675 -1750);
FORCEPROP 1 LAST VOLTAGE 25V
J 0
(-1800 -1750);
DISPLAY 0.617021 (-1800 -1750);
PAINT SKYBLUE (-1800 -1750);
FORCEPROP 1 LAST VALUE 0.1UF
J 2
(-1825 -1750);
DISPLAY 0.617021 (-1825 -1750);
PAINT SKYBLUE (-1825 -1750);
FORCEPROP 1 LAST TOLERANCE 10%
J 2
(-1525 -1725);
DISPLAY 0.617021 (-1525 -1725);
PAINT SKYBLUE (-1525 -1725);
FORCEPROP 1 LAST MATERIAL X7R
J 0
(-1675 -1725);
DISPLAY 0.617021 (-1675 -1725);
PAINT SKYBLUE (-1675 -1725);
FORCEPROP 1 LAST LOCATION PC1358
J 1
(-2250 -1750);
DISPLAY 0.617021 (-2250 -1750);
PAINT AQUA (-2250 -1750);
FORCEPROP 1 LASTPIN (-2150 -1750) $PN 1
J 0
(-2160 -1735);
DISPLAY 0.617021 (-2160 -1735);
FORCEPROP 1 LASTPIN (-1950 -1750) $PN 2
J 0
(-1965 -1735);
DISPLAY 0.617021 (-1965 -1735);
FORCEPROP 2 LAST CDS_LIB pure_quanta
J 0
(-2050 -1750);
PAINT MONO (-2050 -1750);
DISPLAY INVISIBLE (-2050 -1750);
FORCEPROP 1 LAST PATH I6
J 0
(-2050 -1550);
DISPLAY 0.978723 (-2050 -1550);
PAINT WHITE (-2050 -1550);
DISPLAY INVISIBLE (-2050 -1550);
FORCEPROP 2 LAST $SEC 1
J 0
(-2050 -1500);
DISPLAY 0.680851 (-2050 -1500);
PAINT MONO (-2050 -1500);
DISPLAY INVISIBLE (-2050 -1500);
FORCEPROP 2 LAST CDS_SEC 1
J 0
(-2050 -1500);
DISPLAY 1.021277 (-2050 -1500);
DISPLAY INVISIBLE (-2050 -1500);
FORCEADD UNIVERSAL_GND..1
(4050 -2125);
FORCEPROP 3 LASTPIN (4050 -2075) SIG_NAME GND\g
J 0
(4060 -2065);
DISPLAY 0.659574 (4060 -2065);
PAINT MONO (4060 -2065);
DISPLAY INVISIBLE (4060 -2065);
FORCEPROP 1 LAST HDL_POWER GND
J 1
(4075 -2200);
DISPLAY 0.872340 (4075 -2200);
PAINT GREEN (4075 -2200);
DISPLAY INVISIBLE (4075 -2200);
FORCEPROP 2 LAST CDS_LIB logical_power
J 0
(4050 -2125);
PAINT MONO (4050 -2125);
DISPLAY INVISIBLE (4050 -2125);
FORCEPROP 1 LAST PATH I60
J 0
(4125 -2125);
DISPLAY 0.872340 (4125 -2125);
PAINT AQUA (4125 -2125);
DISPLAY INVISIBLE (4125 -2125);
FORCEADD VCC15..1
(4050 -1350);
FORCEPROP 3 LASTPIN (4050 -1400) SIG_NAME PVCCIN_CPU1\g
J 0
(4060 -1390);
DISPLAY 0.659574 (4060 -1390);
PAINT MONO (4060 -1390);
DISPLAY INVISIBLE (4060 -1390);
FORCEPROP 1 LAST HDL_POWER PVCCIN_CPU1
J 1
(4050 -1300);
DISPLAY 0.617021 (4050 -1300);
PAINT GREEN (4050 -1300);
FORCEPROP 2 LAST CDS_LIB logical_power
J 0
(4050 -1350);
DISPLAY INVISIBLE (4050 -1350);
FORCEPROP 1 LAST PATH I61
J 0
(4100 -1325);
DISPLAY 0.872340 (4100 -1325);
PAINT AQUA (4100 -1325);
DISPLAY INVISIBLE (4100 -1325);
FORCEADD UNIVERSAL_GND..1
(4200 700);
FORCEPROP 3 LASTPIN (4200 750) SIG_NAME GND\g
J 0
(4210 760);
DISPLAY 0.659574 (4210 760);
PAINT MONO (4210 760);
DISPLAY INVISIBLE (4210 760);
FORCEPROP 1 LAST HDL_POWER GND
J 1
(4225 625);
DISPLAY 0.872340 (4225 625);
PAINT GREEN (4225 625);
DISPLAY INVISIBLE (4225 625);
FORCEPROP 2 LAST CDS_LIB logical_power
J 0
(4200 700);
PAINT MONO (4200 700);
DISPLAY INVISIBLE (4200 700);
FORCEPROP 1 LAST PATH I62
J 0
(4275 700);
DISPLAY 0.872340 (4275 700);
PAINT AQUA (4275 700);
DISPLAY INVISIBLE (4275 700);
FORCEADD Q_CAP..1
(3475 1075);
FORCEPROP 1 LAST PART_NUMBER CH622KMEA03
J 0
(3525 900);
DISPLAY 0.617021 (3525 900);
PAINT BLUE (3525 900);
DISPLAY INVISIBLE (3525 900);
FORCEPROP 1 LAST PACK_TYPE C0805
J 0
(3525 950);
DISPLAY 0.617021 (3525 950);
PAINT SKYBLUE (3525 950);
FORCEPROP 1 LAST TOLERANCE 20%
J 0
(3525 1050);
DISPLAY 0.617021 (3525 1050);
PAINT SKYBLUE (3525 1050);
FORCEPROP 1 LAST MATERIAL X6S
J 0
(3525 1000);
DISPLAY 0.617021 (3525 1000);
PAINT SKYBLUE (3525 1000);
FORCEPROP 1 LAST VALUE 22UF
J 0
(3525 1150);
DISPLAY 0.617021 (3525 1150);
PAINT SKYBLUE (3525 1150);
FORCEPROP 1 LAST VOLTAGE 4V
J 0
(3525 1100);
DISPLAY 0.617021 (3525 1100);
PAINT SKYBLUE (3525 1100);
FORCEPROP 1 LAST LOCATION PC542_P1_3
J 0
(3525 1200);
DISPLAY 0.617021 (3525 1200);
PAINT AQUA (3525 1200);
FORCEPROP 1 LASTPIN (3475 1175) $PN 1
J 0
(3485 1155);
DISPLAY 0.617021 (3485 1155);
PAINT MONO (3485 1155);
FORCEPROP 1 LASTPIN (3475 975) $PN 2
J 0
(3485 955);
DISPLAY 0.617021 (3485 955);
PAINT MONO (3485 955);
FORCEPROP 2 LAST CDS_LIB pure_quanta
J 0
(3475 1075);
DISPLAY INVISIBLE (3475 1075);
FORCEPROP 1 LAST PATH I63
J 0
(3525 1225);
DISPLAY 0.978723 (3525 1225);
PAINT WHITE (3525 1225);
DISPLAY INVISIBLE (3525 1225);
FORCEPROP 1 LAST LOCATION PC542_P1_3
J 0
(3525 1250);
DISPLAY 1.021277 (3525 1250);
PAINT AQUA (3525 1250);
DISPLAY INVISIBLE (3525 1250);
FORCEPROP 0 LAST $SEC 1
J 0
(3525 1250);
DISPLAY 0.680851 (3525 1250);
PAINT MONO (3525 1250);
DISPLAY INVISIBLE (3525 1250);
FORCEPROP 0 LAST CDS_SEC 1
J 0
(3525 1250);
DISPLAY 1.021277 (3525 1250);
DISPLAY INVISIBLE (3525 1250);
FORCEADD Q_CAP..1
(3900 1075);
FORCEPROP 1 LAST PART_NUMBER CH622KMEA03
J 0
(3950 900);
DISPLAY 0.617021 (3950 900);
PAINT BLUE (3950 900);
DISPLAY INVISIBLE (3950 900);
FORCEPROP 1 LAST PACK_TYPE C0805
J 0
(3950 950);
DISPLAY 0.617021 (3950 950);
PAINT SKYBLUE (3950 950);
FORCEPROP 1 LAST MATERIAL X6S
J 0
(3950 1000);
DISPLAY 0.617021 (3950 1000);
PAINT SKYBLUE (3950 1000);
FORCEPROP 1 LAST TOLERANCE 20%
J 0
(3950 1050);
DISPLAY 0.617021 (3950 1050);
PAINT SKYBLUE (3950 1050);
FORCEPROP 1 LAST VALUE 22UF
J 0
(3950 1150);
DISPLAY 0.617021 (3950 1150);
PAINT SKYBLUE (3950 1150);
FORCEPROP 1 LAST VOLTAGE 4V
J 0
(3950 1100);
DISPLAY 0.617021 (3950 1100);
PAINT SKYBLUE (3950 1100);
FORCEPROP 1 LAST LOCATION PC544_P1_3
J 0
(3950 1200);
DISPLAY 0.617021 (3950 1200);
PAINT AQUA (3950 1200);
FORCEPROP 1 LASTPIN (3900 1175) $PN 1
J 0
(3910 1155);
DISPLAY 0.617021 (3910 1155);
PAINT MONO (3910 1155);
FORCEPROP 1 LASTPIN (3900 975) $PN 2
J 0
(3910 955);
DISPLAY 0.617021 (3910 955);
PAINT MONO (3910 955);
FORCEPROP 2 LAST CDS_LIB pure_quanta
J 0
(3900 1075);
DISPLAY INVISIBLE (3900 1075);
FORCEPROP 1 LAST PATH I64
J 0
(3950 1225);
DISPLAY 0.978723 (3950 1225);
PAINT WHITE (3950 1225);
DISPLAY INVISIBLE (3950 1225);
FORCEPROP 1 LAST LOCATION PC544_P1_3
J 0
(3950 1250);
DISPLAY 1.021277 (3950 1250);
PAINT AQUA (3950 1250);
DISPLAY INVISIBLE (3950 1250);
FORCEPROP 0 LAST $SEC 1
J 0
(3950 1250);
DISPLAY 0.680851 (3950 1250);
PAINT MONO (3950 1250);
DISPLAY INVISIBLE (3950 1250);
FORCEPROP 0 LAST CDS_SEC 1
J 0
(3950 1250);
DISPLAY 1.021277 (3950 1250);
DISPLAY INVISIBLE (3950 1250);
FORCEADD VCC15..1
(4200 1475);
FORCEPROP 3 LASTPIN (4200 1425) SIG_NAME PVCCIN_CPU1\g
J 0
(4210 1435);
DISPLAY 0.659574 (4210 1435);
PAINT MONO (4210 1435);
DISPLAY INVISIBLE (4210 1435);
FORCEPROP 1 LAST HDL_POWER PVCCIN_CPU1
J 1
(4200 1525);
DISPLAY 0.617021 (4200 1525);
PAINT GREEN (4200 1525);
FORCEPROP 2 LAST CDS_LIB logical_power
J 0
(4200 1475);
DISPLAY INVISIBLE (4200 1475);
FORCEPROP 1 LAST PATH I65
J 0
(4250 1500);
DISPLAY 0.872340 (4250 1500);
PAINT AQUA (4250 1500);
DISPLAY INVISIBLE (4250 1500);
FORCEADD ISL99390FRZTR5935..1
(-825 1275);
FORCEPROP 1 LAST PART_NUMBER AL099390004
J 0
(-1125 2075);
DISPLAY 0.617021 (-1125 2075);
PAINT BLUE (-1125 2075);
DISPLAY INVISIBLE (-1125 2075);
FORCEPROP 2 LAST VALUE ISL99390FRZ-TR5935
J 0
(-1125 2225);
DISPLAY 0.617021 (-1125 2225);
PAINT SKYBLUE (-1125 2225);
FORCEPROP 1 LAST MATERIAL IC
J 0
(-1125 2000);
DISPLAY 0.617021 (-1125 2000);
PAINT SKYBLUE (-1125 2000);
FORCEPROP 2 LAST PART_TYPE SMLF
J 0
(-1125 2275);
DISPLAY 0.638298 (-1125 2275);
FORCEPROP 1 LAST LOCATION PU28_P1_3
J 0
(-1125 2150);
DISPLAY 0.617021 (-1125 2150);
PAINT AQUA (-1125 2150);
FORCEPROP 2 LASTPIN (-425 825) $PN 2
J 0
(-415 835);
DISPLAY 0.617021 (-415 835);
PAINT MONO (-415 835);
FORCEPROP 2 LASTPIN (-425 1625) $PN 33
J 0
(-415 1635);
DISPLAY 0.617021 (-415 1635);
PAINT MONO (-415 1635);
FORCEPROP 2 LASTPIN (-1275 1025) $PN 31
J 2
(-1285 1035);
DISPLAY 0.617021 (-1285 1035);
PAINT MONO (-1285 1035);
FORCEPROP 2 LASTPIN (-1275 1425) $PN 35
J 2
(-1285 1435);
DISPLAY 0.617021 (-1285 1435);
PAINT MONO (-1285 1435);
FORCEPROP 2 LASTPIN (-425 975) $PN 6
J 0
(-415 985);
DISPLAY 0.617021 (-415 985);
PAINT MONO (-415 985);
FORCEPROP 2 LASTPIN (-425 925) $PN 41
J 0
(-415 935);
DISPLAY 0.617021 (-415 935);
PAINT MONO (-415 935);
FORCEPROP 2 LASTPIN (-1275 1275) $PN 38
J 2
(-1285 1285);
DISPLAY 0.617021 (-1285 1285);
PAINT MONO (-1285 1285);
FORCEPROP 2 LASTPIN (-1275 975) $PN 37
J 2
(-1285 985);
DISPLAY 0.617021 (-1285 985);
PAINT MONO (-1285 985);
FORCEPROP 2 LASTPIN (-425 775) $PN 5
J 0
(-415 785);
DISPLAY 0.617021 (-415 785);
PAINT MONO (-415 785);
FORCEPROP 2 LASTPIN (-425 725) $PN 7_9-20_24
J 0
(-415 735);
DISPLAY 0.617021 (-415 735);
PAINT MONO (-415 735);
FORCEPROP 2 LASTPIN (-425 675) $PN 40
J 0
(-415 685);
DISPLAY 0.617021 (-415 685);
PAINT MONO (-415 685);
FORCEPROP 2 LASTPIN (-425 1375) $PN 32
J 0
(-415 1385);
DISPLAY 0.617021 (-415 1385);
PAINT MONO (-415 1385);
FORCEPROP 2 LASTPIN (-1275 1925) $PN 4
J 2
(-1285 1935);
DISPLAY 0.617021 (-1285 1935);
PAINT MONO (-1285 1935);
FORCEPROP 2 LASTPIN (-1275 675) $PN 34
J 2
(-1285 685);
DISPLAY 0.617021 (-1285 685);
PAINT MONO (-1285 685);
FORCEPROP 2 LASTPIN (-1275 1175) $PN 39
J 2
(-1285 1185);
DISPLAY 0.617021 (-1285 1185);
PAINT MONO (-1285 1185);
FORCEPROP 2 LASTPIN (-425 1275) $PN 10_19
J 0
(-415 1285);
DISPLAY 0.617021 (-415 1285);
PAINT MONO (-415 1285);
FORCEPROP 2 LASTPIN (-1275 775) $PN 36
J 2
(-1285 785);
DISPLAY 0.617021 (-1285 785);
PAINT MONO (-1285 785);
FORCEPROP 2 LASTPIN (-1275 1625) $PN 3
J 2
(-1285 1635);
DISPLAY 0.617021 (-1285 1635);
PAINT MONO (-1285 1635);
FORCEPROP 2 LASTPIN (-425 1925) $PN 25_29
J 0
(-415 1935);
DISPLAY 0.617021 (-415 1935);
PAINT MONO (-415 1935);
FORCEPROP 2 LASTPIN (-425 1875) $PN 30
J 0
(-415 1885);
DISPLAY 0.617021 (-415 1885);
PAINT MONO (-415 1885);
FORCEPROP 2 LASTPIN (-425 1025) $PN 1
J 0
(-415 1035);
DISPLAY 0.617021 (-415 1035);
PAINT MONO (-415 1035);
FORCEPROP 1 LAST NEEDS_NO_SIZE TRUE
J 0
(-825 1275);
DISPLAY 0.723404 (-825 1275);
PAINT GREEN (-825 1275);
DISPLAY INVISIBLE (-825 1275);
FORCEPROP 1 LAST CDS_LMAN_SYM_OUTLINE -300,700,250,-650
J 0
(-825 1275);
DISPLAY 0.468085 (-825 1275);
PAINT GREEN (-825 1275);
DISPLAY INVISIBLE (-825 1275);
FORCEPROP 2 LAST CDS_LIB pure_quanta
J 0
(-825 1275);
DISPLAY INVISIBLE (-825 1275);
FORCEPROP 1 LAST PATH I66
J 0
(-825 1275);
DISPLAY 0.723404 (-825 1275);
PAINT GREEN (-825 1275);
DISPLAY INVISIBLE (-825 1275);
FORCEPROP 2 LAST $SEC 1
J 0
(-1100 2200);
DISPLAY 0.680851 (-1100 2200);
PAINT MONO (-1100 2200);
DISPLAY INVISIBLE (-1100 2200);
FORCEPROP 2 LAST CDS_SEC 1
J 0
(-1100 2200);
DISPLAY 1.021277 (-1100 2200);
DISPLAY INVISIBLE (-1100 2200);
FORCEADD OFFPAGE..5
(-2300 -1550);
FORCEPROP 2 LAST $XR0 284 
J 0
(-2555 -1550);
DISPLAY 0.638298 (-2555 -1550);
PAINT MONO (-2555 -1550);
FORCEPROP 1 LAST COMMENT_BODY TRUE
J 0
(-2200 -1625);
DISPLAY 0.872340 (-2200 -1625);
PAINT GREEN (-2200 -1625);
DISPLAY INVISIBLE (-2200 -1625);
FORCEPROP 1 LAST OFFPAGE TRUE
J 0
(-1975 -1675);
DISPLAY 0.872340 (-1975 -1675);
PAINT GREEN (-1975 -1675);
DISPLAY INVISIBLE (-1975 -1675);
FORCEPROP 2 LAST CDS_LIB standard
J 0
(-2300 -1550);
DISPLAY INVISIBLE (-2300 -1550);
FORCEPROP 2 LAST PATH I7
J 0
(-2550 -1500);
DISPLAY 1.021277 (-2550 -1500);
DISPLAY INVISIBLE (-2550 -1500);
FORCEADD OFFPAGE..1
(-2300 -1650);
FORCEPROP 2 LAST $XR6 290 
J 0
(-3302 -1650);
DISPLAY 0.638298 (-3302 -1650);
PAINT MONO (-3302 -1650);
FORCEPROP 2 LAST $XR5 289 
J 0
(-3182 -1650);
DISPLAY 0.638298 (-3182 -1650);
PAINT MONO (-3182 -1650);
FORCEPROP 2 LAST $XR4 288 
J 0
(-3062 -1650);
DISPLAY 0.638298 (-3062 -1650);
PAINT MONO (-3062 -1650);
FORCEPROP 2 LAST $XR3 287 
J 0
(-2942 -1650);
DISPLAY 0.638298 (-2942 -1650);
PAINT MONO (-2942 -1650);
FORCEPROP 2 LAST $XR2 286 
J 0
(-2822 -1650);
DISPLAY 0.638298 (-2822 -1650);
PAINT MONO (-2822 -1650);
FORCEPROP 2 LAST $XR1 285 
J 0
(-2702 -1650);
DISPLAY 0.638298 (-2702 -1650);
PAINT MONO (-2702 -1650);
FORCEPROP 2 LAST $XR0 284 
J 0
(-2582 -1650);
DISPLAY 0.638298 (-2582 -1650);
PAINT MONO (-2582 -1650);
FORCEPROP 1 LAST COMMENT_BODY TRUE
J 0
(-2175 -1750);
DISPLAY 0.872340 (-2175 -1750);
PAINT GREEN (-2175 -1750);
DISPLAY INVISIBLE (-2175 -1750);
FORCEPROP 1 LAST OFFPAGE TRUE
J 0
(-1975 -1775);
DISPLAY 0.872340 (-1975 -1775);
PAINT GREEN (-1975 -1775);
DISPLAY INVISIBLE (-1975 -1775);
FORCEPROP 2 LAST CDS_LIB standard
J 0
(-2300 -1650);
DISPLAY INVISIBLE (-2300 -1650);
FORCEPROP 2 LAST PATH I8
J 0
(-2575 -1600);
DISPLAY 1.021277 (-2575 -1600);
DISPLAY INVISIBLE (-2575 -1600);
FORCEADD UNIVERSAL_GND..1
(-2375 -1300);
FORCEPROP 3 LASTPIN (-2375 -1250) SIG_NAME GND\g
J 0
(-2365 -1240);
DISPLAY 0.659574 (-2365 -1240);
PAINT MONO (-2365 -1240);
DISPLAY INVISIBLE (-2365 -1240);
FORCEPROP 1 LAST HDL_POWER GND
J 1
(-2350 -1375);
DISPLAY 0.872340 (-2350 -1375);
PAINT GREEN (-2350 -1375);
DISPLAY INVISIBLE (-2350 -1375);
FORCEPROP 2 LAST CDS_LIB logical_power
J 0
(-2375 -1300);
PAINT MONO (-2375 -1300);
DISPLAY INVISIBLE (-2375 -1300);
FORCEPROP 1 LAST PATH I9
J 0
(-2300 -1300);
DISPLAY 0.872340 (-2300 -1300);
PAINT AQUA (-2300 -1300);
DISPLAY INVISIBLE (-2300 -1300);
FORCEADD DNS..1
(-2775 -2075);
PAINT RED (-2775 -2075);
FORCEPROP 1 LAST COMMENT_BODY TRUE
R 1
J 0
(-2700 -2300);
DISPLAY 0.872340 (-2700 -2300);
PAINT GREEN (-2700 -2300);
DISPLAY INVISIBLE (-2700 -2300);
FORCEPROP 2 LAST CDS_LIB mstr_misc
J 0
(-2775 -2075);
PAINT MONO (-2775 -2075);
DISPLAY INVISIBLE (-2775 -2075);
FORCEADD DNS..1
(-2750 750);
PAINT RED (-2750 750);
FORCEPROP 1 LAST COMMENT_BODY TRUE
R 1
J 0
(-2675 525);
DISPLAY 0.872340 (-2675 525);
PAINT GREEN (-2675 525);
DISPLAY INVISIBLE (-2675 525);
FORCEPROP 2 LAST CDS_LIB mstr_misc
J 0
(-2750 750);
PAINT MONO (-2750 750);
DISPLAY INVISIBLE (-2750 750);
FORCEADD QUANTA_TITLE_BLOCK_C..1
(4625 -3400);
FORCEPROP 0 LAST CDS_CON_LAST_MODIFIED Fri Aug 25 14:04:56 2023
J 0
(2740 -3385);
DISPLAY INVISIBLE (2740 -3385);
FORCEPROP 1 LAST CUSTOM_TXT_CDS <CON_LAST_MODIFIED>
J 0
(2740 -3385);
DISPLAY 0.978723 (2740 -3385);
FORCEPROP 2 LAST CUSTOM_TXT_CDS <XR_PAGE_TITLE>
J 0
(-3265 1850);
DISPLAY 0.638298 (-3265 1850);
PAINT PINK (-3265 1850);
DISPLAY INVISIBLE (-3265 1850);
FORCEPROP 1 LAST CUSTOM_TXT_CDS <NAME_2>
J 0
(1450 -3350);
FORCEPROP 1 LAST CUSTOM_TXT_CDS <NAME_1>
J 0
(1450 -3225);
FORCEPROP 1 LAST CUSTOM_TXT_CDS <Q_NUMBER>
J 0
(3222 -3297);
DISPLAY 1.212766 (3222 -3297);
FORCEPROP 1 LAST CUSTOM_TXT_CDS <Q_PROJ>
J 0
(2243 -3298);
DISPLAY 1.212766 (2243 -3298);
FORCEPROP 1 LAST CUSTOM_TXT_CDS <Q_REV>
J 0
(4441 -3297);
DISPLAY 1.212766 (4441 -3297);
FORCEPROP 1 LAST CUSTOM_TXT_CDS <CON_PAGE_NUM> OF <CON_TOTAL_PAGES>
J 0
(4179 -3382);
DISPLAY 0.978723 (4179 -3382);
FORCEPROP 1 LAST Q_TITLE VCCIN CPU1 VR PHASE 3&4 (3/7)
J 0
(-4675 -3350);
DISPLAY 2.446809 (-4675 -3350);
PAINT GREEN (-4675 -3350);
FORCEPROP 1 LAST Q_DEPT 
J 1
(862 -3351);
DISPLAY 1.957447 (862 -3351);
PAINT GREEN (862 -3351);
FORCEPROP 2 LAST CDS_XR_PAGE_TITLE CR-286 : @S9S_MB_2U_LIB.S9S_MB_2U(SCH_1):PAGE286
J 0
(-3265 1850);
DISPLAY 0.638298 (-3265 1850);
PAINT PINK (-3265 1850);
DISPLAY INVISIBLE (-3265 1850);
FORCEPROP 2 LAST CDS_LIB pure_quanta
J 0
(4625 -3400);
DISPLAY INVISIBLE (4625 -3400);
FORCEPROP 1 LAST CDS_LMAN_SYM_OUTLINE -9475,6775,100,-125
J 0
(4625 -3400);
DISPLAY 0.468085 (4625 -3400);
PAINT GREEN (4625 -3400);
DISPLAY INVISIBLE (4625 -3400);
FORCEPROP 2 LAST PAGE_BORDER TRUE
J 0
(-3265 1850);
DISPLAY 0.638298 (-3265 1850);
PAINT PINK (-3265 1850);
DISPLAY INVISIBLE (-3265 1850);
FORCEPROP 1 LAST COMMENT_BODY TRUE
J 0
(4637 -3413);
DISPLAY 0.978723 (4637 -3413);
PAINT GREEN (4637 -3413);
DISPLAY INVISIBLE (4637 -3413);
WIRE 16 -1 (-2375 -325)(-2375 -275);
WIRE 16 -1 (-1950 -325)(-2375 -325);
WIRE 16 -1 (-2375 -450)(-2375 -325);
WIRE 16 -1 (-2350 2500)(-2350 2550);
WIRE 16 -1 (-1925 2500)(-2350 2500);
WIRE 16 -1 (-2350 2375)(-2350 2500);
WIRE 16 -1 (1750 -325)(1750 -400);
WIRE 16 -1 (1775 2500)(1775 2425);
WIRE 16 -1 (4050 -1400)(4050 -1550);
WIRE 16 -1 (4200 1425)(4200 1275);
WIRE 16 -1 (-2775 -2150)(-2775 -2225);
WIRE 16 -1 (-2875 -1750)(-2875 -1775);
WIRE 16 -1 (-2875 -1750)(-2150 -1750);
WIRE 16 -1 (-2375 -1150)(-2375 -1250);
WIRE 16 -1 (-2750 675)(-2750 600);
WIRE 16 -1 (-1950 -650)(-1950 -725);
WIRE 16 -1 (-2850 1075)(-2850 1050);
WIRE 16 -1 (-2850 1075)(-2125 1075);
WIRE 16 -1 (-2350 1675)(-2350 1575);
WIRE 16 -1 (-1925 2175)(-1925 2100);
WIRE 16 -1 (-200 -2150)(-200 -2225);
WIRE 16 -1 (-200 -2100)(-200 -2150);
WIRE 16 -1 (-450 -2150)(-200 -2150);
WIRE 16 -1 (-175 675)(-175 600);
WIRE 16 -1 (-175 725)(-175 675);
WIRE 16 -1 (-425 675)(-175 675);
WIRE 16 -1 (1750 -1025)(1750 -900);
WIRE 16 -1 (1775 1800)(1775 1925);
WIRE 16 -1 (4050 -2075)(4050 -1975);
WIRE 16 -1 (4200 750)(4200 850);
WIRE 16 -1 (-2775 -1850)(-2775 -1950);
WIRE 16 -1 (-2775 -1850)(-1300 -1850);
FORCEPROP 2 LAST SIG_NAME PVCCIN_CPU1_LSET4
J 0
(-2135 -1840);
DISPLAY 0.617021 (-2135 -1840);
WIRE 16 -1 (-1300 -2150)(-2250 -2150);
FORCEPROP 2 LAST SIG_NAME PVCCIN_CPU1_PWM4
J 0
(-2135 -2140);
DISPLAY 0.617021 (-2135 -2140);
WIRE 16 -1 (-1300 -2050)(-2250 -2050);
FORCEPROP 2 LAST SIG_NAME PVCCIN_CPU1_ATSEN
J 0
(-2135 -2040);
DISPLAY 0.617021 (-2135 -2040);
WIRE 16 -1 (-1300 -1550)(-2250 -1550);
FORCEPROP 2 LAST SIG_NAME PVCCIN_CPU1_IMON4
J 0
(-2135 -1540);
DISPLAY 0.617021 (-2135 -1540);
WIRE 16 -1 (-1400 -1750)(-1950 -1750);
WIRE 16 -1 (-2250 -1650)(-1400 -1650);
FORCEPROP 2 LAST SIG_NAME PVCCIN_CPU1_VREF
J 0
(-2135 -1640);
DISPLAY 0.617021 (-2135 -1640);
WIRE 16 -1 (-1400 -1650)(-1300 -1650);
WIRE 16 -1 (-1400 -1650)(-1400 -1750);
FORCEPROP 0 LAST CDS_PHYS_NET_NAME PVCCIN_CPU1_VREF
J 0
(-1400 -1725);
PAINT MONO (-1400 -1725);
DISPLAY INVISIBLE (-1400 -1725);
WIRE 16 -1 (-1300 -1400)(-1400 -1400);
WIRE 16 -1 (-1400 -1400)(-1400 -1200);
WIRE 16 -1 (-1300 -1200)(-1400 -1200);
WIRE 16 -1 (-1400 -1200)(-1975 -1200);
FORCEPROP 2 LAST SIG_NAME PVCCIN_CPU1_VDD4
J 0
(-1935 -1190);
DISPLAY 0.617021 (-1935 -1190);
WIRE 16 -1 (-1975 -1200)(-1975 -800);
WIRE 16 -1 (-2375 -800)(-2375 -950);
WIRE 16 -1 (-2375 -650)(-2375 -800);
WIRE 16 -1 (-2375 -800)(-1975 -800);
WIRE 16 -1 (-1275 675)(-2225 675);
FORCEPROP 2 LAST SIG_NAME PVCCIN_CPU1_PWM3
J 0
(-2110 685);
DISPLAY 0.617021 (-2110 685);
WIRE 16 -1 (-1275 775)(-2225 775);
FORCEPROP 2 LAST SIG_NAME PVCCIN_CPU1_ATSEN
J 0
(-2110 785);
DISPLAY 0.617021 (-2110 785);
WIRE 16 -1 (-1950 -325)(-1950 -450);
WIRE 16 -1 (-1375 -325)(-1950 -325);
WIRE 16 -1 (-1375 -900)(-1375 -325);
WIRE 16 -1 (-1300 -900)(-1375 -900);
WIRE 16 -1 (-2750 975)(-2750 875);
WIRE 16 -1 (-2750 975)(-1275 975);
FORCEPROP 2 LAST SIG_NAME PVCCIN_CPU1_LSET3
J 0
(-2110 985);
DISPLAY 0.617021 (-2110 985);
WIRE 16 -1 (-1275 1275)(-2225 1275);
FORCEPROP 2 LAST SIG_NAME PVCCIN_CPU1_IMON3
J 0
(-2110 1285);
DISPLAY 0.617021 (-2110 1285);
WIRE 16 -1 (-2350 2025)(-2350 1875);
WIRE 16 -1 (-2350 2175)(-2350 2025);
WIRE 16 -1 (-2350 2025)(-1950 2025);
WIRE 16 -1 (-1950 1625)(-1950 2025);
WIRE 16 -1 (-1950 1625)(-1375 1625);
FORCEPROP 2 LAST SIG_NAME PVCCIN_CPU1_VDD3
J 0
(-1910 1635);
DISPLAY 0.617021 (-1910 1635);
WIRE 16 -1 (-1375 1625)(-1275 1625);
WIRE 16 -1 (-1375 1425)(-1375 1625);
WIRE 16 -1 (-1275 1425)(-1375 1425);
WIRE 16 -1 (-1925 2500)(-1925 2375);
WIRE 16 -1 (-1350 2500)(-1925 2500);
WIRE 16 -1 (-1350 1925)(-1350 2500);
WIRE 16 -1 (-1275 1925)(-1350 1925);
WIRE 16 -1 (-450 -2100)(-200 -2100);
WIRE 16 -1 (-450 -2050)(-200 -2050);
WIRE 16 -1 (-200 -2050)(-200 -2100);
WIRE 16 -1 (-200 -2000)(-200 -2050);
WIRE 16 -1 (-450 -2000)(-200 -2000);
WIRE 16 -1 (-450 -1800)(-50 -1800);
WIRE 16 -1 (-50 -1800)(-50 -2175);
WIRE 16 -1 (1425 -2175)(-50 -2175);
FORCEPROP 2 LAST SIG_NAME PVCCIN_CPU1_VOS4
J 0
(515 -2150);
DISPLAY 0.617021 (515 -2150);
WIRE 16 -1 (-450 -1200)(-300 -1200);
WIRE 16 -1 (-300 -1200)(-300 -1100);
FORCEPROP 2 LAST SIG_NAME SW_PVCCIN_CPU1_BOOT4
J 0
(-410 -1090);
DISPLAY 0.617021 (-410 -1090);
WIRE 16 -1 (-300 -1100)(300 -1100);
FORCEPROP 0 LAST CDS_PHYS_NET_NAME SW_PVCCIN_CPU1_BOOT4
J 0
(-260 -1071);
PAINT MONO (-260 -1071);
DISPLAY INVISIBLE (-260 -1071);
WIRE 16 -1 (-425 725)(-175 725);
WIRE 16 -1 (-425 775)(-175 775);
WIRE 16 -1 (-175 775)(-175 725);
WIRE 16 -1 (-175 825)(-175 775);
WIRE 16 -1 (-425 825)(-175 825);
WIRE 16 -1 (500 -1100)(1125 -1100);
FORCEPROP 2 LAST SIG_NAME SW_PVCCIN_CPU1_BOOT4_R
J 0
(690 -1090);
DISPLAY 0.617021 (690 -1090);
WIRE 16 -1 (1125 -1100)(1125 -1175);
WIRE 16 -1 (-450 -1450)(1125 -1450);
FORCEPROP 0 LAST CDS_PHYS_NET_NAME SW_PVCCIN_CPU1_BOOTR4
J 0
(-260 -1410);
PAINT MONO (-260 -1410);
DISPLAY INVISIBLE (-260 -1410);
FORCEPROP 2 LAST SIG_NAME SW_PVCCIN_CPU1_BOOTR4
J 0
(-260 -1440);
DISPLAY 0.617021 (-260 -1440);
WIRE 16 -1 (1125 -1450)(1125 -1375);
WIRE 16 -1 (400 -1800)(1200 -1800);
FORCEPROP 2 LAST SIG_NAME IND_P1_CPL4
J 0
(540 -1790);
DISPLAY 0.617021 (540 -1790);
WIRE 16 -1 (-450 -1550)(1200 -1550);
FORCEPROP 2 LAST SIG_NAME SW_PVCCIN_CPU1_SW4
J 0
(-260 -1540);
DISPLAY 0.617021 (-260 -1540);
WIRE 16 -1 (2000 -1800)(2750 -1800);
FORCEPROP 2 LAST SIG_NAME IND_P1_CPL3
J 0
(2090 -1790);
DISPLAY 0.617021 (2090 -1790);
WIRE 16 -1 (-50 -750)(-50 -900);
WIRE 16 -1 (-50 -900)(350 -900);
WIRE 16 -1 (350 -750)(350 -900);
WIRE 16 -1 (750 -900)(350 -900);
WIRE 16 -1 (750 -750)(750 -900);
WIRE 16 -1 (750 -900)(1150 -900);
WIRE 16 -1 (1150 -750)(1150 -900);
WIRE 16 -1 (1150 -900)(1525 -900);
WIRE 16 -1 (1525 -750)(1525 -900);
WIRE 16 -1 (1750 -900)(1525 -900);
WIRE 16 -1 (-450 -950)(-275 -950);
WIRE 16 -1 (-275 -950)(-275 -900);
WIRE 16 -1 (-450 -900)(-275 -900);
WIRE 16 -1 (-275 -400)(-275 -900);
WIRE 16 -1 (-50 -550)(-50 -400);
WIRE 16 -1 (-275 -400)(-50 -400);
WIRE 16 -1 (-50 -400)(350 -400);
WIRE 16 -1 (350 -550)(350 -400);
WIRE 16 -1 (350 -400)(750 -400);
WIRE 16 -1 (750 -400)(750 -550);
WIRE 16 -1 (750 -400)(1150 -400);
WIRE 16 -1 (1150 -550)(1150 -400);
WIRE 16 -1 (1525 -550)(1525 -400);
WIRE 16 -1 (1150 -400)(1525 -400);
WIRE 16 -1 (1750 -400)(1525 -400);
WIRE 16 -1 (1475 650)(0 650);
FORCEPROP 2 LAST SIG_NAME PVCCIN_CPU1_VOS3
J 0
(240 660);
DISPLAY 0.617021 (240 660);
WIRE 16 -1 (0 1025)(0 650);
WIRE 16 -1 (-425 1025)(0 1025);
WIRE 16 -1 (-425 1625)(-275 1625);
WIRE 16 -1 (-275 1625)(-275 1725);
FORCEPROP 2 LAST SIG_NAME SW_PVCCIN_CPU1_BOOT3
J 0
(-385 1735);
DISPLAY 0.617021 (-385 1735);
WIRE 16 -1 (-275 1725)(325 1725);
FORCEPROP 0 LAST CDS_PHYS_NET_NAME SW_PVCCIN_CPU1_BOOT3
J 0
(-235 1754);
PAINT MONO (-235 1754);
DISPLAY INVISIBLE (-235 1754);
WIRE 16 -1 (525 1725)(1150 1725);
FORCEPROP 2 LAST SIG_NAME SW_PVCCIN_CPU1_BOOT3_R
J 0
(715 1735);
DISPLAY 0.617021 (715 1735);
WIRE 16 -1 (1150 1725)(1150 1650);
WIRE 16 -1 (700 1025)(1225 1025);
FORCEPROP 2 LAST SIG_NAME IND_P1_CPL3
J 0
(765 1035);
DISPLAY 0.617021 (765 1035);
WIRE 16 -1 (-425 1375)(1150 1375);
FORCEPROP 0 LAST CDS_PHYS_NET_NAME SW_PVCCIN_CPU1_BOOTR3
J 0
(-235 1415);
PAINT MONO (-235 1415);
DISPLAY INVISIBLE (-235 1415);
FORCEPROP 2 LAST SIG_NAME SW_PVCCIN_CPU1_BOOTR3
J 0
(-235 1385);
DISPLAY 0.617021 (-235 1385);
WIRE 16 -1 (1150 1375)(1150 1450);
WIRE 16 -1 (-425 1275)(1225 1275);
FORCEPROP 2 LAST SIG_NAME SW_PVCCIN_CPU1_SW3
J 0
(-235 1285);
DISPLAY 0.617021 (-235 1285);
WIRE 16 -1 (-25 2075)(-25 1925);
WIRE 16 -1 (-25 1925)(375 1925);
WIRE 16 -1 (375 2075)(375 1925);
WIRE 16 -1 (775 1925)(375 1925);
WIRE 16 -1 (775 2075)(775 1925);
WIRE 16 -1 (775 1925)(1175 1925);
WIRE 16 -1 (1175 2075)(1175 1925);
WIRE 16 -1 (1175 1925)(1550 1925);
WIRE 16 -1 (1550 2075)(1550 1925);
WIRE 16 -1 (1775 1925)(1550 1925);
WIRE 16 -1 (-425 1875)(-250 1875);
WIRE 16 -1 (-425 1925)(-250 1925);
WIRE 16 -1 (-250 1875)(-250 1925);
WIRE 16 -1 (-250 2425)(-250 1925);
WIRE 16 -1 (-25 2275)(-25 2425);
WIRE 16 -1 (-250 2425)(-25 2425);
WIRE 16 -1 (-25 2425)(375 2425);
WIRE 16 -1 (375 2275)(375 2425);
WIRE 16 -1 (375 2425)(775 2425);
WIRE 16 -1 (775 2425)(775 2275);
WIRE 16 -1 (775 2425)(1175 2425);
WIRE 16 -1 (1175 2275)(1175 2425);
WIRE 16 -1 (1175 2425)(1550 2425);
WIRE 16 -1 (1550 2275)(1550 2425);
WIRE 16 -1 (1775 2425)(1550 2425);
WIRE 16 -1 (2025 1025)(2525 1025);
FORCEPROP 2 LAST SIG_NAME IND_P1_CPL2
J 0
(2115 1035);
DISPLAY 0.617021 (2115 1035);
WIRE 16 -1 (1625 -2175)(3075 -2175);
WIRE 16 -1 (3075 -1550)(2000 -1550);
WIRE 16 -1 (3075 -2175)(3075 -1550);
WIRE 16 -1 (3325 -1550)(3075 -1550);
WIRE 16 -1 (3325 -1550)(3325 -1650);
WIRE 16 -1 (3325 -1550)(3750 -1550);
WIRE 16 -1 (3750 -1550)(3750 -1650);
WIRE 16 -1 (3750 -1550)(4050 -1550);
WIRE 16 -1 (3325 -1975)(3325 -1850);
WIRE 16 -1 (3750 -1975)(3325 -1975);
WIRE 16 -1 (3750 -1975)(3750 -1850);
WIRE 16 -1 (4050 -1975)(3750 -1975);
WIRE 16 -1 (3475 850)(3475 975);
WIRE 16 -1 (3900 850)(3475 850);
WIRE 16 -1 (3900 975)(3900 850);
WIRE 16 -1 (4200 850)(3900 850);
WIRE 16 -1 (1675 650)(3200 650);
WIRE 16 -1 (3200 1275)(2025 1275);
WIRE 16 -1 (3200 650)(3200 1275);
WIRE 16 -1 (3475 1275)(3200 1275);
WIRE 16 -1 (3475 1275)(3475 1175);
WIRE 16 -1 (3475 1275)(3900 1275);
WIRE 16 -1 (3900 1175)(3900 1275);
WIRE 16 -1 (4200 1275)(3900 1275);
WIRE 16 -1 (-1375 1075)(-1925 1075);
WIRE 16 -1 (-2225 1175)(-1375 1175);
FORCEPROP 2 LAST SIG_NAME PVCCIN_CPU1_VREF
J 0
(-2110 1185);
DISPLAY 0.617021 (-2110 1185);
WIRE 16 -1 (-1375 1175)(-1375 1075);
FORCEPROP 0 LAST CDS_PHYS_NET_NAME PVCCIN_CPU1_VREF
J 0
(-1375 1100);
PAINT MONO (-1375 1100);
DISPLAY INVISIBLE (-1375 1100);
WIRE 16 -1 (-1375 1175)(-1275 1175);
DOT 1 (-1400 -1650);
DOT 1 (-1400 -1200);
DOT 1 (-2375 -800);
DOT 1 (-2375 -325);
DOT 1 (-1950 -325);
DOT 1 (-2350 2025);
DOT 1 (-2350 2500);
DOT 1 (-1375 1175);
DOT 1 (-1375 1625);
DOT 1 (-1925 2500);
DOT 1 (-200 -2100);
DOT 1 (-200 -2050);
DOT 1 (-200 -2150);
DOT 1 (-275 -900);
DOT 1 (-175 675);
DOT 1 (-175 725);
DOT 1 (-175 775);
DOT 1 (350 -900);
DOT 1 (-50 -400);
DOT 1 (350 -400);
DOT 1 (750 -900);
DOT 1 (750 -400);
DOT 1 (1150 -900);
DOT 1 (1150 -400);
DOT 1 (1525 -900);
DOT 1 (1525 -400);
DOT 1 (-250 1925);
DOT 1 (375 1925);
DOT 1 (375 2425);
DOT 1 (-25 2425);
DOT 1 (775 1925);
DOT 1 (775 2425);
DOT 1 (1175 1925);
DOT 1 (1175 2425);
DOT 1 (1550 1925);
DOT 1 (1550 2425);
DOT 1 (3075 -1550);
DOT 1 (3325 -1550);
DOT 1 (3750 -1975);
DOT 1 (3750 -1550);
DOT 1 (3900 850);
DOT 1 (3200 1275);
DOT 1 (3475 1275);
DOT 1 (3900 1275);
FORCENOTE
PVCCIN_CPU1_PHASE4
(-1225 -400) 0;
DISPLAY LEFT (-1225 -400);
DISPLAY 1.021277 (-1225 -400);
PAINT WHITE (-1225 -400);
FORCENOTE
PVCCIN_CPU1_PHASE3
(-1225 2425) 0;
DISPLAY LEFT (-1225 2425);
DISPLAY 1.021277 (-1225 2425);
PAINT WHITE (-1225 2425);
FORCENOTE
DCR=2-3,0.27M OHM
(1900 -1450) 0;
DISPLAY LEFT (1900 -1450);
DISPLAY 1.021277 (1900 -1450);
FORCENOTE
DCR=1-4,0.105M OHM
(1900 -1375) 0;
DISPLAY LEFT (1900 -1375);
DISPLAY 1.021277 (1900 -1375);
FORCENOTE
ISAT=70A@100C
(1900 -1300) 0;
DISPLAY LEFT (1900 -1300);
DISPLAY 1.021277 (1900 -1300);
FORCENOTE
11.0*7.5*12.5
(1900 -1225) 0;
DISPLAY LEFT (1900 -1225);
DISPLAY 1.021277 (1900 -1225);
FORCENOTE
PGL6303.151HLT 
(1900 -1150) 0;
DISPLAY LEFT (1900 -1150);
DISPLAY 1.021277 (1900 -1150);
FORCENOTE
DCR=2-3,0.27M OHM
(1925 1400) 0;
DISPLAY LEFT (1925 1400);
DISPLAY 1.021277 (1925 1400);
FORCENOTE
DCR=1-4,0.105M OHM
(1925 1475) 0;
DISPLAY LEFT (1925 1475);
DISPLAY 1.021277 (1925 1475);
FORCENOTE
ISAT=70A@100C
(1925 1550) 0;
DISPLAY LEFT (1925 1550);
DISPLAY 1.021277 (1925 1550);
FORCENOTE
11.0*7.5*12.5
(1925 1625) 0;
DISPLAY LEFT (1925 1625);
DISPLAY 1.021277 (1925 1625);
FORCENOTE
PGL6303.151HLT 
(1925 1700) 0;
DISPLAY LEFT (1925 1700);
DISPLAY 1.021277 (1925 1700);
QUIT
